FILE_TYPE = MACRO_DRAWING;
SET COLOR_WIRE YELLOW;
SET COLOR_PROP ORANGE;
SET COLOR_DOT WHITE;
SET COLOR_ARC YELLOW;
SET COLOR_BODY GREEN;
SET COLOR_NOTE PURPLE;
SET PROP_DISPLAY VALUE;
SET PAGE_NUMBER P239;
FORCEADD UNIVERSAL_GND..1
(6000 3350);
FORCEPROP 3 LASTPIN (6000 3400) SIG_NAME GND\g
J 0
(6010 3410);
DISPLAY 0.659574 (6010 3410);
PAINT MONO (6010 3410);
DISPLAY INVISIBLE (6010 3410);
FORCEPROP 1 LAST HDL_POWER GND
J 1
(6025 3275);
DISPLAY 0.872340 (6025 3275);
PAINT GREEN (6025 3275);
DISPLAY INVISIBLE (6025 3275);
FORCEPROP 1 LAST PATH I101
J 0
(6075 3350);
DISPLAY 0.872340 (6075 3350);
PAINT AQUA (6075 3350);
DISPLAY INVISIBLE (6075 3350);
FORCEPROP 2 LAST CDS_LIB logical_power
J 0
(6000 3350);
DISPLAY INVISIBLE (6000 3350);
FORCEADD UNIVERSAL_GND..1
(4975 3400);
FORCEPROP 3 LASTPIN (4975 3450) SIG_NAME GND\g
J 0
(4985 3460);
DISPLAY 0.659574 (4985 3460);
PAINT MONO (4985 3460);
DISPLAY INVISIBLE (4985 3460);
FORCEPROP 1 LAST HDL_POWER GND
J 1
(5000 3325);
DISPLAY 0.872340 (5000 3325);
PAINT GREEN (5000 3325);
DISPLAY INVISIBLE (5000 3325);
FORCEPROP 1 LAST PATH I102
J 0
(5050 3400);
DISPLAY 0.872340 (5050 3400);
PAINT AQUA (5050 3400);
DISPLAY INVISIBLE (5050 3400);
FORCEPROP 2 LAST CDS_LIB logical_power
J 0
(4975 3400);
DISPLAY INVISIBLE (4975 3400);
FORCEADD ADC128D818CIMTXNOPB..1
(6275 1300);
FORCEPROP 1 LAST PART_NUMBER AL000128K00
J 0
(6022 1869);
DISPLAY 0.723404 (6022 1869);
PAINT GREEN (6022 1869);
DISPLAY INVISIBLE (6022 1869);
FORCEPROP 2 LAST PART_TYPE SMLF
J 0
(6025 2050);
DISPLAY 1.021277 (6025 2050);
FORCEPROP 2 LAST VALUE ADC128D818CIMTX/NOPB
J 0
(6025 2000);
DISPLAY 1.021277 (6025 2000);
FORCEPROP 2 LAST ROOM ADC1_BOM2
J 0
(6025 2100);
DISPLAY 1.021277 (6025 2100);
FORCEPROP 1 LAST MATERIAL IC
J 0
(6022 1780);
DISPLAY 0.723404 (6022 1780);
PAINT RED (6022 1780);
FORCEPROP 1 LAST $LOCATION U269
J 0
(6022 1953);
DISPLAY 0.723404 (6022 1953);
PAINT GREEN (6022 1953);
FORCEPROP 0 LASTPIN (5875 1325) $PN 7
J 2
(5865 1335);
DISPLAY 0.680851 (5865 1335);
PAINT MONO (5865 1335);
FORCEPROP 0 LASTPIN (5875 1375) $PN 8
J 2
(5865 1385);
DISPLAY 0.680851 (5865 1385);
PAINT MONO (5865 1385);
FORCEPROP 0 LASTPIN (6675 875) $PN 4
J 0
(6685 885);
DISPLAY 0.680851 (6685 885);
PAINT MONO (6685 885);
FORCEPROP 0 LASTPIN (5875 875) $PN 16
J 2
(5865 885);
DISPLAY 0.680851 (5865 885);
PAINT MONO (5865 885);
FORCEPROP 0 LASTPIN (5875 925) $PN 15
J 2
(5865 935);
DISPLAY 0.680851 (5865 935);
PAINT MONO (5865 935);
FORCEPROP 0 LASTPIN (5875 975) $PN 14
J 2
(5865 985);
DISPLAY 0.680851 (5865 985);
PAINT MONO (5865 985);
FORCEPROP 0 LASTPIN (5875 1025) $PN 13
J 2
(5865 1035);
DISPLAY 0.680851 (5865 1035);
PAINT MONO (5865 1035);
FORCEPROP 0 LASTPIN (5875 1075) $PN 12
J 2
(5865 1085);
DISPLAY 0.680851 (5865 1085);
PAINT MONO (5865 1085);
FORCEPROP 0 LASTPIN (5875 1125) $PN 11
J 2
(5865 1135);
DISPLAY 0.680851 (5865 1135);
PAINT MONO (5865 1135);
FORCEPROP 0 LASTPIN (5875 1175) $PN 10
J 2
(5865 1185);
DISPLAY 0.680851 (5865 1185);
PAINT MONO (5865 1185);
FORCEPROP 0 LASTPIN (5875 1225) $PN 9
J 2
(5865 1235);
DISPLAY 0.680851 (5865 1235);
PAINT MONO (5865 1235);
FORCEPROP 0 LASTPIN (6675 1725) $PN 6
J 0
(6685 1735);
DISPLAY 0.680851 (6685 1735);
PAINT MONO (6685 1735);
FORCEPROP 0 LASTPIN (5875 1625) $PN 3
J 2
(5865 1635);
DISPLAY 0.680851 (5865 1635);
PAINT MONO (5865 1635);
FORCEPROP 0 LASTPIN (5875 1575) $PN 2
J 2
(5865 1585);
DISPLAY 0.680851 (5865 1585);
PAINT MONO (5865 1585);
FORCEPROP 0 LASTPIN (5875 1725) $PN 5
J 2
(5865 1735);
DISPLAY 0.680851 (5865 1735);
PAINT MONO (5865 1735);
FORCEPROP 0 LASTPIN (5875 1475) $PN 1
J 2
(5865 1485);
DISPLAY 0.680851 (5865 1485);
PAINT MONO (5865 1485);
FORCEPROP 2 LAST CDS_LIB pure_quanta
J 0
(6275 1300);
DISPLAY INVISIBLE (6275 1300);
FORCEPROP 1 LAST PATH I103
J 0
(6275 1300);
DISPLAY 0.723404 (6275 1300);
PAINT GREEN (6275 1300);
DISPLAY INVISIBLE (6275 1300);
FORCEPROP 1 LAST CDS_LMAN_SYM_OUTLINE -250,475,250,-475
J 0
(6275 1300);
DISPLAY 0.468085 (6275 1300);
PAINT GREEN (6275 1300);
DISPLAY INVISIBLE (6275 1300);
FORCEPROP 1 LAST PIN_NAMES_ROTATE True
J 0
(6275 1300);
DISPLAY 0.489362 (6275 1300);
PAINT GREEN (6275 1300);
DISPLAY INVISIBLE (6275 1300);
FORCEPROP 0 LAST CDS_LOCATION U269
J 0
(6025 2100);
DISPLAY 1.021277 (6025 2100);
DISPLAY INVISIBLE (6025 2100);
FORCEPROP 0 LAST $SEC 1
J 0
(6025 2100);
DISPLAY 0.680851 (6025 2100);
PAINT MONO (6025 2100);
DISPLAY INVISIBLE (6025 2100);
FORCEPROP 0 LAST CDS_SEC 1
J 0
(6025 2100);
DISPLAY 1.021277 (6025 2100);
DISPLAY INVISIBLE (6025 2100);
FORCEADD OFFPAGE..3
(7400 250);
FORCEPROP 2 LAST $XR0 250 
J 0
(7614 250);
DISPLAY 0.638298 (7614 250);
PAINT MONO (7614 250);
FORCEPROP 2 LAST PATH I108
J 0
(7625 300);
DISPLAY 1.021277 (7625 300);
DISPLAY INVISIBLE (7625 300);
FORCEPROP 1 LAST COMMENT_BODY TRUE
J 0
(7350 150);
DISPLAY 0.872340 (7350 150);
PAINT GREEN (7350 150);
DISPLAY INVISIBLE (7350 150);
FORCEPROP 1 LAST OFFPAGE TRUE
J 0
(7725 125);
DISPLAY 0.872340 (7725 125);
PAINT GREEN (7725 125);
DISPLAY INVISIBLE (7725 125);
FORCEPROP 2 LAST CDS_LIB standard
J 0
(7400 250);
DISPLAY INVISIBLE (7400 250);
FORCEADD OFFPAGE..2
(7400 200);
FORCEPROP 2 LAST $XR0 250 
J 0
(7589 200);
DISPLAY 0.638298 (7589 200);
PAINT MONO (7589 200);
FORCEPROP 2 LAST PATH I109
J 0
(7625 250);
DISPLAY 1.021277 (7625 250);
DISPLAY INVISIBLE (7625 250);
FORCEPROP 1 LAST COMMENT_BODY TRUE
J 0
(7355 105);
DISPLAY 0.872340 (7355 105);
PAINT GREEN (7355 105);
DISPLAY INVISIBLE (7355 105);
FORCEPROP 1 LAST OFFPAGE TRUE
J 0
(7725 75);
DISPLAY 0.872340 (7725 75);
DISPLAY INVISIBLE (7725 75);
FORCEPROP 2 LAST CDS_LIB standard
J 0
(7400 200);
DISPLAY INVISIBLE (7400 200);
FORCEADD Q_RES..1
(6350 250);
FORCEPROP 1 LAST PART_NUMBER CS00002JB13
J 0
(6250 125);
DISPLAY 0.404255 (6250 125);
DISPLAY INVISIBLE (6250 125);
FORCEPROP 1 LAST VALUE 0
J 2
(6500 250);
DISPLAY 0.404255 (6500 250);
FORCEPROP 1 LAST TOLERANCE 5%
J 0
(6525 250);
DISPLAY 0.404255 (6525 250);
FORCEPROP 1 LAST MATERIAL CHIP
J 0
(6575 250);
DISPLAY 0.404255 (6575 250);
PAINT RED (6575 250);
FORCEPROP 1 LAST PACK_TYPE 0402LF
J 0
(6250 150);
DISPLAY 0.404255 (6250 150);
FORCEPROP 1 LAST WATTAGE 1/16W
J 2
(6475 150);
DISPLAY 0.404255 (6475 150);
FORCEPROP 2 LAST ROOM ADC1_BOM2
J 0
(6250 300);
DISPLAY 0.638298 (6250 300);
FORCEPROP 1 LAST $LOCATION R3671
J 0
(6150 250);
DISPLAY 0.510638 (6150 250);
FORCEPROP 1 LASTPIN (6250 250) $PN 1
J 0
(6262 262);
DISPLAY 0.787234 (6262 262);
PAINT MONO (6262 262);
FORCEPROP 1 LASTPIN (6450 250) $PN 2
J 0
(6412 262);
DISPLAY 0.787234 (6412 262);
PAINT MONO (6412 262);
FORCEPROP 1 LAST PATH I110
J 0
(6300 400);
DISPLAY 0.978723 (6300 400);
PAINT WHITE (6300 400);
DISPLAY INVISIBLE (6300 400);
FORCEPROP 2 LAST CDS_LIB pure_quanta
J 0
(6350 250);
DISPLAY INVISIBLE (6350 250);
FORCEPROP 0 LAST CDS_LOCATION R3671
J 0
(6575 275);
DISPLAY 1.021277 (6575 275);
DISPLAY INVISIBLE (6575 275);
FORCEPROP 0 LAST $SEC 1
J 0
(6575 275);
DISPLAY 0.680851 (6575 275);
PAINT MONO (6575 275);
DISPLAY INVISIBLE (6575 275);
FORCEPROP 0 LAST CDS_SEC 1
J 0
(6575 275);
DISPLAY 1.021277 (6575 275);
DISPLAY INVISIBLE (6575 275);
FORCEADD Q_RES..1
(6350 200);
FORCEPROP 1 LAST PART_NUMBER CS00002JB13
J 0
(6275 150);
DISPLAY 0.319149 (6275 150);
DISPLAY INVISIBLE (6275 150);
FORCEPROP 1 LAST TOLERANCE 5%
J 0
(6525 200);
DISPLAY 0.404255 (6525 200);
FORCEPROP 1 LAST MATERIAL CHIP
J 0
(6575 200);
DISPLAY 0.404255 (6575 200);
PAINT RED (6575 200);
FORCEPROP 1 LAST VALUE 0
J 2
(6500 200);
DISPLAY 0.404255 (6500 200);
FORCEPROP 2 LAST ROOM ADC1_BOM2
J 0
(6250 75);
DISPLAY 0.638298 (6250 75);
FORCEPROP 1 LAST $LOCATION R3672
J 0
(6150 200);
DISPLAY 0.510638 (6150 200);
FORCEPROP 1 LASTPIN (6250 200) $PN 1
J 0
(6262 212);
DISPLAY 0.787234 (6262 212);
PAINT MONO (6262 212);
FORCEPROP 1 LASTPIN (6450 200) $PN 2
J 0
(6412 212);
DISPLAY 0.787234 (6412 212);
PAINT MONO (6412 212);
FORCEPROP 1 LAST PATH I111
J 0
(6300 350);
DISPLAY 0.978723 (6300 350);
PAINT WHITE (6300 350);
DISPLAY INVISIBLE (6300 350);
FORCEPROP 1 LAST WATTAGE 1/16W
J 2
(6450 125);
DISPLAY 0.319149 (6450 125);
DISPLAY INVISIBLE (6450 125);
FORCEPROP 2 LAST CDS_LIB pure_quanta
J 0
(6350 200);
DISPLAY INVISIBLE (6350 200);
FORCEPROP 1 LAST PACK_TYPE 0402LF
J 0
(6600 200);
DISPLAY 0.510638 (6600 200);
DISPLAY INVISIBLE (6600 200);
FORCEPROP 0 LAST CDS_LOCATION R3672
J 0
(6575 225);
DISPLAY 1.021277 (6575 225);
DISPLAY INVISIBLE (6575 225);
FORCEPROP 0 LAST $SEC 1
J 0
(6575 225);
DISPLAY 0.680851 (6575 225);
PAINT MONO (6575 225);
DISPLAY INVISIBLE (6575 225);
FORCEPROP 0 LAST CDS_SEC 1
J 0
(6575 225);
DISPLAY 1.021277 (6575 225);
DISPLAY INVISIBLE (6575 225);
FORCEADD OFFPAGE..3
R 2
(5350 250);
FORCEPROP 2 LAST $XR1 250 
J 0
(4950 250);
DISPLAY 0.638298 (4950 250);
PAINT MONO (4950 250);
FORCEPROP 2 LAST $XR0 241 
J 0
(5070 250);
DISPLAY 0.638298 (5070 250);
PAINT MONO (5070 250);
FORCEPROP 2 LAST PATH I112
J 0
(5075 300);
DISPLAY 1.021277 (5075 300);
DISPLAY INVISIBLE (5075 300);
FORCEPROP 2 LAST CDS_LIB standard
J 0
(5350 250);
PAINT MONO (5350 250);
DISPLAY INVISIBLE (5350 250);
FORCEPROP 1 LAST OFFPAGE TRUE
J 2
(5025 125);
DISPLAY 0.872340 (5025 125);
DISPLAY INVISIBLE (5025 125);
FORCEPROP 1 LAST COMMENT_BODY TRUE
J 2
(5400 150);
DISPLAY 0.872340 (5400 150);
PAINT GREEN (5400 150);
DISPLAY INVISIBLE (5400 150);
FORCEADD OFFPAGE..1
(5350 200);
FORCEPROP 2 LAST $XR1 250 
J 0
(4948 200);
DISPLAY 0.638298 (4948 200);
PAINT MONO (4948 200);
FORCEPROP 2 LAST $XR0 241 
J 0
(5068 200);
DISPLAY 0.638298 (5068 200);
PAINT MONO (5068 200);
FORCEPROP 2 LAST PATH I113
J 0
(5075 250);
DISPLAY 1.021277 (5075 250);
DISPLAY INVISIBLE (5075 250);
FORCEPROP 2 LAST CDS_LIB standard
J 0
(5350 200);
PAINT MONO (5350 200);
DISPLAY INVISIBLE (5350 200);
FORCEPROP 1 LAST OFFPAGE TRUE
J 0
(5675 75);
DISPLAY 0.872340 (5675 75);
PAINT GREEN (5675 75);
DISPLAY INVISIBLE (5675 75);
FORCEPROP 1 LAST COMMENT_BODY TRUE
J 0
(5475 100);
DISPLAY 0.872340 (5475 100);
PAINT GREEN (5475 100);
DISPLAY INVISIBLE (5475 100);
FORCEADD OFFPAGE..3
R 2
(5150 1575);
FORCEPROP 2 LAST $XR0 250 
J 0
(4870 1575);
DISPLAY 0.638298 (4870 1575);
PAINT MONO (4870 1575);
FORCEPROP 2 LAST CDS_LIB standard
J 2
(5150 1575);
DISPLAY INVISIBLE (5150 1575);
FORCEPROP 1 LAST OFFPAGE TRUE
J 2
(4825 1450);
DISPLAY 0.872340 (4825 1450);
PAINT GREEN (4825 1450);
DISPLAY INVISIBLE (4825 1450);
FORCEPROP 1 LAST COMMENT_BODY TRUE
J 2
(5200 1475);
DISPLAY 0.872340 (5200 1475);
PAINT GREEN (5200 1475);
DISPLAY INVISIBLE (5200 1475);
FORCEPROP 2 LAST PATH I114
J 2
(4925 1625);
DISPLAY 1.021277 (4925 1625);
DISPLAY INVISIBLE (4925 1625);
FORCEADD OFFPAGE..4
R 2
(5150 1625);
FORCEPROP 2 LAST $XR0 250 
J 0
(4898 1625);
DISPLAY 0.638298 (4898 1625);
PAINT MONO (4898 1625);
FORCEPROP 2 LAST CDS_LIB standard
J 2
(5150 1625);
DISPLAY INVISIBLE (5150 1625);
FORCEPROP 2 LAST PATH I115
J 2
(4950 1675);
DISPLAY 1.021277 (4950 1675);
DISPLAY INVISIBLE (4950 1675);
FORCEPROP 1 LAST COMMENT_BODY TRUE
J 2
(5175 1525);
DISPLAY 0.872340 (5175 1525);
PAINT GREEN (5175 1525);
DISPLAY INVISIBLE (5175 1525);
FORCEPROP 1 LAST OFFPAGE TRUE
J 2
(4825 1500);
DISPLAY 0.872340 (4825 1500);
DISPLAY INVISIBLE (4825 1500);
FORCEADD UNIVERSAL_POWER..1
(3250 2150);
FORCEPROP 3 LASTPIN (3250 2100) SIG_NAME P3V3_AUX\g
J 0
(3260 2110);
DISPLAY 0.659574 (3260 2110);
PAINT MONO (3260 2110);
DISPLAY INVISIBLE (3260 2110);
FORCEPROP 1 LAST HDL_POWER P3V3_AUX
J 1
(3250 2200);
DISPLAY 0.872340 (3250 2200);
PAINT GREEN (3250 2200);
FORCEPROP 1 LAST PATH I117
J 0
(3300 2175);
DISPLAY 0.872340 (3300 2175);
PAINT AQUA (3300 2175);
DISPLAY INVISIBLE (3300 2175);
FORCEPROP 2 LAST CDS_LIB logical_power
J 0
(3250 2150);
DISPLAY INVISIBLE (3250 2150);
FORCEADD Q_INDUCTOR..1
(3550 1925);
FORCEPROP 1 LAST PART_NUMBER TMP_QCX8PG300001
J 0
(3450 2035);
DISPLAY 0.382979 (3450 2035);
PAINT GREEN (3450 2035);
DISPLAY INVISIBLE (3450 2035);
FORCEPROP 1 LAST MATERIAL IND
J 0
(3450 1980);
DISPLAY 0.382979 (3450 1980);
PAINT RED (3450 1980);
FORCEPROP 2 LAST ROOM ADC1_BOM2
J 0
(3450 2200);
DISPLAY 0.638298 (3450 2200);
FORCEPROP 2 LAST VALUE BLM18PG300SN1D 
J 0
(3450 2175);
DISPLAY 0.510638 (3450 2175);
FORCEPROP 2 LAST PACK_TYPE SMLF
J 0
(3450 2125);
DISPLAY 0.510638 (3450 2125);
FORCEPROP 1 LAST $LOCATION L16
J 0
(3425 2085);
DISPLAY 0.723404 (3425 2085);
PAINT GREEN (3425 2085);
FORCEPROP 0 LASTPIN (3450 1900) $PN 1
J 2
(3440 1910);
DISPLAY 0.680851 (3440 1910);
PAINT MONO (3440 1910);
FORCEPROP 0 LASTPIN (3650 1900) $PN 2
J 0
(3660 1910);
DISPLAY 0.680851 (3660 1910);
PAINT MONO (3660 1910);
FORCEPROP 2 LAST CDS_LIB pure_quanta
J 0
(3550 1925);
DISPLAY INVISIBLE (3550 1925);
FORCEPROP 1 LAST PATH I118
J 0
(3625 1980);
DISPLAY 0.723404 (3625 1980);
PAINT GREEN (3625 1980);
DISPLAY INVISIBLE (3625 1980);
FORCEPROP 1 LAST NEEDS_NO_SIZE TRUE
J 0
(3550 1925);
DISPLAY 0.468085 (3550 1925);
PAINT GREEN (3550 1925);
DISPLAY INVISIBLE (3550 1925);
FORCEPROP 0 LAST CDS_LOCATION L16
J 0
(3450 2200);
DISPLAY 1.021277 (3450 2200);
DISPLAY INVISIBLE (3450 2200);
FORCEPROP 0 LAST $SEC 1
J 0
(3450 2200);
DISPLAY 0.680851 (3450 2200);
PAINT MONO (3450 2200);
DISPLAY INVISIBLE (3450 2200);
FORCEPROP 0 LAST CDS_SEC 1
J 0
(3450 2200);
DISPLAY 1.021277 (3450 2200);
DISPLAY INVISIBLE (3450 2200);
FORCEADD OFFPAGE..1
R 2
(6850 4250);
FORCEPROP 2 LAST $XR0 250 
J 0
(7036 4250);
DISPLAY 0.638298 (7036 4250);
PAINT MONO (7036 4250);
FORCEPROP 2 LAST PATH I125
J 0
(7025 4325);
DISPLAY 1.021277 (7025 4325);
DISPLAY INVISIBLE (7025 4325);
FORCEPROP 1 LAST OFFPAGE TRUE
J 2
(6525 4125);
DISPLAY 0.872340 (6525 4125);
PAINT GREEN (6525 4125);
DISPLAY INVISIBLE (6525 4125);
FORCEPROP 1 LAST COMMENT_BODY TRUE
J 2
(6725 4150);
DISPLAY 0.872340 (6725 4150);
PAINT GREEN (6725 4150);
DISPLAY INVISIBLE (6725 4150);
FORCEPROP 2 LAST CDS_LIB standard
J 0
(6850 4250);
DISPLAY INVISIBLE (6850 4250);
FORCEADD OFFPAGE..1
R 2
(6850 4150);
FORCEPROP 2 LAST $XR0 250 
J 0
(7036 4150);
DISPLAY 0.638298 (7036 4150);
PAINT MONO (7036 4150);
FORCEPROP 2 LAST PATH I126
J 0
(7025 4225);
DISPLAY 1.021277 (7025 4225);
DISPLAY INVISIBLE (7025 4225);
FORCEPROP 2 LAST CDS_LIB standard
J 2
(6850 4150);
DISPLAY INVISIBLE (6850 4150);
FORCEPROP 1 LAST OFFPAGE TRUE
J 2
(6525 4025);
DISPLAY 0.872340 (6525 4025);
PAINT GREEN (6525 4025);
DISPLAY INVISIBLE (6525 4025);
FORCEPROP 1 LAST COMMENT_BODY TRUE
J 2
(6725 4050);
DISPLAY 0.872340 (6725 4050);
PAINT GREEN (6725 4050);
DISPLAY INVISIBLE (6725 4050);
FORCEADD Q_CAP..1
R 2
(3725 1700);
FORCEPROP 1 LAST PART_NUMBER CH4104K1B00
J 2
(4025 1575);
DISPLAY 0.510638 (4025 1575);
DISPLAY INVISIBLE (4025 1575);
FORCEPROP 1 LAST VALUE 0.1UF
J 2
(3900 1775);
DISPLAY 0.510638 (3900 1775);
FORCEPROP 1 LAST VOLTAGE 25V
J 2
(3875 1725);
DISPLAY 0.510638 (3875 1725);
FORCEPROP 1 LAST TOLERANCE 10%
J 2
(3875 1675);
DISPLAY 0.510638 (3875 1675);
FORCEPROP 1 LAST MATERIAL X7R
J 2
(3875 1625);
DISPLAY 0.510638 (3875 1625);
PAINT RED (3875 1625);
FORCEPROP 1 LAST PACK_TYPE 0402
J 2
(3900 1525);
DISPLAY 0.510638 (3900 1525);
FORCEPROP 2 LAST ROOM ADC1_BOM2
J 0
(3775 1475);
DISPLAY 0.638298 (3775 1475);
FORCEPROP 1 LAST $LOCATION C2051
J 2
(3950 1825);
DISPLAY 0.978723 (3950 1825);
FORCEPROP 1 LASTPIN (3725 1800) $PN 1
J 2
(3715 1780);
DISPLAY 0.787234 (3715 1780);
PAINT MONO (3715 1780);
FORCEPROP 1 LASTPIN (3725 1600) $PN 2
J 2
(3715 1580);
DISPLAY 0.787234 (3715 1580);
PAINT MONO (3715 1580);
FORCEPROP 2 LAST CDS_LIB pure_quanta
J 0
(3725 1700);
DISPLAY INVISIBLE (3725 1700);
FORCEPROP 1 LAST PATH I127
J 2
(3675 1850);
DISPLAY 0.978723 (3675 1850);
PAINT WHITE (3675 1850);
DISPLAY INVISIBLE (3675 1850);
FORCEPROP 0 LAST CDS_LOCATION C2051
J 0
(3825 1850);
DISPLAY 1.021277 (3825 1850);
DISPLAY INVISIBLE (3825 1850);
FORCEPROP 0 LAST $SEC 1
J 0
(3825 1850);
DISPLAY 0.680851 (3825 1850);
PAINT MONO (3825 1850);
DISPLAY INVISIBLE (3825 1850);
FORCEPROP 0 LAST CDS_SEC 1
J 0
(3825 1850);
DISPLAY 1.021277 (3825 1850);
DISPLAY INVISIBLE (3825 1850);
FORCEADD Q_CAP..1
(4050 1700);
FORCEPROP 1 LAST PART_NUMBER CH4104K1B00
J 0
(4100 1550);
DISPLAY 0.510638 (4100 1550);
DISPLAY INVISIBLE (4100 1550);
FORCEPROP 1 LAST MATERIAL X7R
J 0
(4100 1600);
DISPLAY 0.510638 (4100 1600);
PAINT RED (4100 1600);
FORCEPROP 1 LAST PACK_TYPE 0402
J 0
(4100 1500);
DISPLAY 0.510638 (4100 1500);
FORCEPROP 1 LAST TOLERANCE 10%
J 0
(4100 1650);
DISPLAY 0.510638 (4100 1650);
FORCEPROP 2 LAST ROOM ADC1_BOM2
J 0
(4100 1850);
DISPLAY 0.638298 (4100 1850);
FORCEPROP 1 LAST VALUE 0.1UF
J 0
(4100 1750);
DISPLAY 0.510638 (4100 1750);
FORCEPROP 1 LAST VOLTAGE 25V
J 0
(4100 1700);
DISPLAY 0.510638 (4100 1700);
FORCEPROP 1 LAST $LOCATION C2052
J 0
(4100 1800);
DISPLAY 0.978723 (4100 1800);
FORCEPROP 1 LASTPIN (4050 1800) $PN 1
J 0
(4060 1780);
DISPLAY 0.787234 (4060 1780);
PAINT MONO (4060 1780);
FORCEPROP 1 LASTPIN (4050 1600) $PN 2
J 0
(4060 1580);
DISPLAY 0.787234 (4060 1580);
PAINT MONO (4060 1580);
FORCEPROP 2 LAST CDS_LIB pure_quanta
J 0
(4050 1700);
DISPLAY INVISIBLE (4050 1700);
FORCEPROP 1 LAST PATH I128
J 0
(4100 1850);
DISPLAY 0.978723 (4100 1850);
PAINT WHITE (4100 1850);
DISPLAY INVISIBLE (4100 1850);
FORCEPROP 0 LAST CDS_LOCATION C2052
J 0
(4100 1850);
DISPLAY 1.021277 (4100 1850);
DISPLAY INVISIBLE (4100 1850);
FORCEPROP 0 LAST $SEC 1
J 0
(4100 1850);
DISPLAY 0.680851 (4100 1850);
PAINT MONO (4100 1850);
DISPLAY INVISIBLE (4100 1850);
FORCEPROP 0 LAST CDS_SEC 1
J 0
(4100 1850);
DISPLAY 1.021277 (4100 1850);
DISPLAY INVISIBLE (4100 1850);
FORCEADD Q_RES..2
(4425 1700);
FORCEPROP 1 LAST PART_NUMBER CS24702FB06
J 0
(4465 1575);
DISPLAY 0.510638 (4465 1575);
DISPLAY INVISIBLE (4465 1575);
FORCEPROP 1 LAST VALUE 4.7K
J 0
(4470 1775);
DISPLAY 0.510638 (4470 1775);
FORCEPROP 1 LAST TOLERANCE 1%
J 0
(4470 1725);
DISPLAY 0.510638 (4470 1725);
FORCEPROP 1 LAST PACK_TYPE 0402LF
J 0
(4465 1525);
DISPLAY 0.510638 (4465 1525);
FORCEPROP 1 LAST MATERIAL EMPTY
J 0
(4465 1625);
DISPLAY 0.510638 (4465 1625);
PAINT RED (4465 1625);
FORCEPROP 1 LAST WATTAGE 1/16W
J 0
(4465 1675);
DISPLAY 0.510638 (4465 1675);
FORCEPROP 1 LAST $LOCATION R3689
J 0
(4470 1825);
DISPLAY 0.638298 (4470 1825);
FORCEPROP 1 LASTPIN (4425 1800) $PN 1
J 0
(4430 1762);
DISPLAY 0.787234 (4430 1762);
PAINT MONO (4430 1762);
FORCEPROP 1 LASTPIN (4425 1600) $PN 2
J 0
(4430 1610);
DISPLAY 0.787234 (4430 1610);
PAINT MONO (4430 1610);
FORCEPROP 2 LAST CDS_LIB pure_quanta
J 0
(4425 1700);
DISPLAY INVISIBLE (4425 1700);
FORCEPROP 1 LAST PATH I129
J 0
(4475 1875);
DISPLAY 0.978723 (4475 1875);
PAINT WHITE (4475 1875);
DISPLAY INVISIBLE (4475 1875);
FORCEPROP 0 LAST CDS_LOCATION R3689
J 0
(4475 1875);
DISPLAY 1.021277 (4475 1875);
DISPLAY INVISIBLE (4475 1875);
FORCEPROP 0 LAST $SEC 1
J 0
(4475 1875);
DISPLAY 0.680851 (4475 1875);
PAINT MONO (4475 1875);
DISPLAY INVISIBLE (4475 1875);
FORCEPROP 0 LAST CDS_SEC 1
J 0
(4475 1875);
DISPLAY 1.021277 (4475 1875);
DISPLAY INVISIBLE (4475 1875);
FORCEADD UNIVERSAL_GND..1
(3725 1375);
FORCEPROP 3 LASTPIN (3725 1425) SIG_NAME GND\g
J 0
(3735 1435);
DISPLAY 0.659574 (3735 1435);
PAINT MONO (3735 1435);
DISPLAY INVISIBLE (3735 1435);
FORCEPROP 1 LAST PATH I130
J 0
(3800 1375);
DISPLAY 0.872340 (3800 1375);
PAINT AQUA (3800 1375);
DISPLAY INVISIBLE (3800 1375);
FORCEPROP 1 LAST HDL_POWER GND
J 1
(3750 1300);
DISPLAY 0.872340 (3750 1300);
PAINT GREEN (3750 1300);
DISPLAY INVISIBLE (3750 1300);
FORCEPROP 2 LAST CDS_LIB logical_power
J 0
(3725 1375);
DISPLAY INVISIBLE (3725 1375);
FORCEADD Q_RES..2
(4425 1200);
FORCEPROP 1 LAST PART_NUMBER CS24702FB06
J 0
(4465 1075);
DISPLAY 0.638298 (4465 1075);
DISPLAY INVISIBLE (4465 1075);
FORCEPROP 1 LAST WATTAGE 1/16W
J 0
(4465 1175);
DISPLAY 0.638298 (4465 1175);
FORCEPROP 1 LAST VALUE 4.7K
J 0
(4470 1275);
DISPLAY 0.638298 (4470 1275);
FORCEPROP 1 LAST TOLERANCE 1%
J 0
(4470 1225);
DISPLAY 0.638298 (4470 1225);
FORCEPROP 1 LAST MATERIAL EMPTY
J 0
(4465 1125);
DISPLAY 0.638298 (4465 1125);
PAINT RED (4465 1125);
FORCEPROP 1 LAST PACK_TYPE 0402LF
J 0
(4465 1025);
DISPLAY 0.638298 (4465 1025);
FORCEPROP 1 LAST $LOCATION R3690
J 0
(4470 1325);
DISPLAY 0.808511 (4470 1325);
FORCEPROP 1 LASTPIN (4425 1300) $PN 1
J 0
(4430 1262);
DISPLAY 0.787234 (4430 1262);
PAINT MONO (4430 1262);
FORCEPROP 1 LASTPIN (4425 1100) $PN 2
J 0
(4430 1110);
DISPLAY 0.787234 (4430 1110);
PAINT MONO (4430 1110);
FORCEPROP 1 LAST PATH I131
J 0
(4475 1375);
DISPLAY 0.978723 (4475 1375);
PAINT WHITE (4475 1375);
DISPLAY INVISIBLE (4475 1375);
FORCEPROP 2 LAST CDS_LIB pure_quanta
J 0
(4425 1200);
DISPLAY INVISIBLE (4425 1200);
FORCEPROP 0 LAST CDS_LOCATION R3690
J 0
(4475 1375);
DISPLAY 1.021277 (4475 1375);
DISPLAY INVISIBLE (4475 1375);
FORCEPROP 0 LAST $SEC 1
J 0
(4475 1375);
DISPLAY 0.680851 (4475 1375);
PAINT MONO (4475 1375);
DISPLAY INVISIBLE (4475 1375);
FORCEPROP 0 LAST CDS_SEC 1
J 0
(4475 1375);
DISPLAY 1.021277 (4475 1375);
DISPLAY INVISIBLE (4475 1375);
FORCEADD UNIVERSAL_GND..1
(4425 875);
FORCEPROP 3 LASTPIN (4425 925) SIG_NAME GND\g
J 0
(4435 935);
DISPLAY 0.659574 (4435 935);
PAINT MONO (4435 935);
DISPLAY INVISIBLE (4435 935);
FORCEPROP 2 LAST CDS_LIB logical_power
J 0
(4425 875);
DISPLAY INVISIBLE (4425 875);
FORCEPROP 1 LAST PATH I132
J 0
(4500 875);
DISPLAY 0.872340 (4500 875);
PAINT AQUA (4500 875);
DISPLAY INVISIBLE (4500 875);
FORCEPROP 1 LAST HDL_POWER GND
J 1
(4450 800);
DISPLAY 0.872340 (4450 800);
PAINT GREEN (4450 800);
DISPLAY INVISIBLE (4450 800);
FORCEADD UNIVERSAL_GND..1
(6850 675);
FORCEPROP 3 LASTPIN (6850 725) SIG_NAME GND\g
J 0
(6860 735);
DISPLAY 0.659574 (6860 735);
PAINT MONO (6860 735);
DISPLAY INVISIBLE (6860 735);
FORCEPROP 2 LAST CDS_LIB logical_power
J 0
(6850 675);
DISPLAY INVISIBLE (6850 675);
FORCEPROP 1 LAST PATH I133
J 0
(6925 675);
DISPLAY 0.872340 (6925 675);
PAINT AQUA (6925 675);
DISPLAY INVISIBLE (6925 675);
FORCEPROP 1 LAST HDL_POWER GND
J 1
(6875 600);
DISPLAY 0.872340 (6875 600);
PAINT GREEN (6875 600);
DISPLAY INVISIBLE (6875 600);
FORCEADD UNIVERSAL_POWER..1
(-1000 5675);
FORCEPROP 3 LASTPIN (-1000 5625) SIG_NAME P3V3_AUX\g
J 0
(-990 5635);
DISPLAY 0.659574 (-990 5635);
PAINT MONO (-990 5635);
DISPLAY INVISIBLE (-990 5635);
FORCEPROP 1 LAST HDL_POWER P3V3_AUX
J 1
(-1000 5725);
DISPLAY 0.872340 (-1000 5725);
PAINT GREEN (-1000 5725);
FORCEPROP 1 LAST PATH I140
J 0
(-950 5700);
DISPLAY 0.872340 (-950 5700);
PAINT AQUA (-950 5700);
DISPLAY INVISIBLE (-950 5700);
FORCEPROP 2 LAST CDS_LIB logical_power
J 0
(-1000 5675);
DISPLAY INVISIBLE (-1000 5675);
FORCEADD Q_RES..2
(-1000 5425);
FORCEPROP 1 LAST PART_NUMBER CS25112FB04
J 0
(-960 5300);
DISPLAY 0.510638 (-960 5300);
DISPLAY INVISIBLE (-960 5300);
FORCEPROP 1 LAST WATTAGE 1/16W
J 0
(-960 5400);
DISPLAY 0.510638 (-960 5400);
FORCEPROP 1 LAST TOLERANCE 1%
J 0
(-955 5450);
DISPLAY 0.510638 (-955 5450);
FORCEPROP 1 LAST PACK_TYPE 0402LF
J 0
(-960 5250);
DISPLAY 0.510638 (-960 5250);
FORCEPROP 1 LAST MATERIAL CHIP
J 0
(-960 5350);
DISPLAY 0.510638 (-960 5350);
FORCEPROP 1 LAST VALUE 5.11K
J 0
(-955 5500);
DISPLAY 0.510638 (-955 5500);
FORCEPROP 1 LAST $LOCATION R2907
J 0
(-955 5550);
DISPLAY 0.510638 (-955 5550);
FORCEPROP 1 LASTPIN (-1000 5525) $PN 1
J 0
(-995 5487);
DISPLAY 0.787234 (-995 5487);
PAINT MONO (-995 5487);
FORCEPROP 1 LASTPIN (-1000 5325) $PN 2
J 0
(-995 5335);
DISPLAY 0.787234 (-995 5335);
PAINT MONO (-995 5335);
FORCEPROP 1 LAST PATH I141
J 0
(-950 5600);
DISPLAY 0.978723 (-950 5600);
PAINT WHITE (-950 5600);
DISPLAY INVISIBLE (-950 5600);
FORCEPROP 2 LAST CDS_LIB pure_quanta
J 0
(-1000 5425);
DISPLAY INVISIBLE (-1000 5425);
FORCEPROP 2 LAST CDS_LOCATION R2907
J 0
(-950 5650);
DISPLAY 1.021277 (-950 5650);
DISPLAY INVISIBLE (-950 5650);
FORCEPROP 2 LAST $SEC 1
J 0
(-950 5650);
DISPLAY 0.680851 (-950 5650);
PAINT MONO (-950 5650);
DISPLAY INVISIBLE (-950 5650);
FORCEPROP 2 LAST CDS_SEC 1
J 0
(-950 5650);
DISPLAY 1.021277 (-950 5650);
DISPLAY INVISIBLE (-950 5650);
FORCEADD Q_RES..2
(-1000 4900);
FORCEPROP 1 LAST PART_NUMBER CS24702FB06
J 0
(-960 4775);
DISPLAY 0.510638 (-960 4775);
DISPLAY INVISIBLE (-960 4775);
FORCEPROP 1 LAST VALUE 4.7K
J 0
(-955 4975);
DISPLAY 0.510638 (-955 4975);
FORCEPROP 1 LAST WATTAGE 1/16W
J 0
(-960 4875);
DISPLAY 0.510638 (-960 4875);
FORCEPROP 1 LAST TOLERANCE 1%
J 0
(-955 4925);
DISPLAY 0.510638 (-955 4925);
FORCEPROP 1 LAST PACK_TYPE 0402LF
J 0
(-960 4725);
DISPLAY 0.510638 (-960 4725);
FORCEPROP 1 LAST MATERIAL CHIP
J 0
(-960 4825);
DISPLAY 0.510638 (-960 4825);
FORCEPROP 1 LAST $LOCATION R1785
J 0
(-955 5025);
DISPLAY 0.638298 (-955 5025);
FORCEPROP 1 LASTPIN (-1000 5000) $PN 1
J 0
(-995 4962);
DISPLAY 0.787234 (-995 4962);
PAINT MONO (-995 4962);
FORCEPROP 1 LASTPIN (-1000 4800) $PN 2
J 0
(-995 4810);
DISPLAY 0.787234 (-995 4810);
PAINT MONO (-995 4810);
FORCEPROP 1 LAST PATH I149
J 0
(-950 5075);
DISPLAY 0.978723 (-950 5075);
PAINT WHITE (-950 5075);
DISPLAY INVISIBLE (-950 5075);
FORCEPROP 2 LAST CDS_LIB pure_quanta
J 0
(-1000 4900);
DISPLAY INVISIBLE (-1000 4900);
FORCEPROP 0 LAST CDS_LOCATION R1785
J 0
(-950 5075);
DISPLAY 1.021277 (-950 5075);
DISPLAY INVISIBLE (-950 5075);
FORCEPROP 0 LAST $SEC 1
J 0
(-950 5075);
DISPLAY 0.680851 (-950 5075);
PAINT MONO (-950 5075);
DISPLAY INVISIBLE (-950 5075);
FORCEPROP 0 LAST CDS_SEC 1
J 0
(-950 5075);
DISPLAY 1.021277 (-950 5075);
DISPLAY INVISIBLE (-950 5075);
FORCEADD UNIVERSAL_GND..1
(-1000 4550);
FORCEPROP 3 LASTPIN (-1000 4600) SIG_NAME GND\g
J 0
(-990 4610);
DISPLAY 0.659574 (-990 4610);
PAINT MONO (-990 4610);
DISPLAY INVISIBLE (-990 4610);
FORCEPROP 1 LAST PATH I150
J 0
(-925 4550);
DISPLAY 0.872340 (-925 4550);
PAINT AQUA (-925 4550);
DISPLAY INVISIBLE (-925 4550);
FORCEPROP 2 LAST CDS_LIB logical_power
J 0
(-1000 4550);
DISPLAY INVISIBLE (-1000 4550);
FORCEPROP 1 LAST HDL_POWER GND
J 1
(-975 4475);
DISPLAY 0.872340 (-975 4475);
PAINT GREEN (-975 4475);
DISPLAY INVISIBLE (-975 4475);
FORCEADD UNIVERSAL_POWER..1
(-1000 4350);
FORCEPROP 3 LASTPIN (-1000 4300) SIG_NAME P3V3\g
J 0
(-990 4310);
DISPLAY 0.659574 (-990 4310);
PAINT MONO (-990 4310);
DISPLAY INVISIBLE (-990 4310);
FORCEPROP 1 LAST HDL_POWER P3V3
J 1
(-1000 4400);
DISPLAY 0.872340 (-1000 4400);
PAINT GREEN (-1000 4400);
FORCEPROP 2 LAST CDS_LIB logical_power
J 0
(-1000 4350);
DISPLAY INVISIBLE (-1000 4350);
FORCEPROP 1 LAST PATH I160
J 0
(-950 4375);
DISPLAY 0.872340 (-950 4375);
PAINT AQUA (-950 4375);
DISPLAY INVISIBLE (-950 4375);
FORCEADD Q_RES..2
(-1000 4100);
FORCEPROP 1 LAST PART_NUMBER CS25112FB04
J 0
(-960 3975);
DISPLAY 0.510638 (-960 3975);
DISPLAY INVISIBLE (-960 3975);
FORCEPROP 1 LAST TOLERANCE 1%
J 0
(-955 4125);
DISPLAY 0.510638 (-955 4125);
FORCEPROP 1 LAST WATTAGE 1/16W
J 0
(-960 4075);
DISPLAY 0.510638 (-960 4075);
FORCEPROP 1 LAST PACK_TYPE 0402LF
J 0
(-960 3925);
DISPLAY 0.510638 (-960 3925);
FORCEPROP 1 LAST VALUE 5.11K
J 0
(-955 4175);
DISPLAY 0.510638 (-955 4175);
FORCEPROP 1 LAST MATERIAL CHIP
J 0
(-960 4025);
DISPLAY 0.510638 (-960 4025);
FORCEPROP 1 LAST $LOCATION R2908
J 0
(-955 4225);
DISPLAY 0.510638 (-955 4225);
FORCEPROP 1 LASTPIN (-1000 4200) $PN 1
J 0
(-995 4162);
DISPLAY 0.787234 (-995 4162);
PAINT MONO (-995 4162);
FORCEPROP 1 LASTPIN (-1000 4000) $PN 2
J 0
(-995 4010);
DISPLAY 0.787234 (-995 4010);
PAINT MONO (-995 4010);
FORCEPROP 2 LAST CDS_LIB pure_quanta
J 0
(-1000 4100);
DISPLAY INVISIBLE (-1000 4100);
FORCEPROP 1 LAST PATH I161
J 0
(-950 4275);
DISPLAY 0.978723 (-950 4275);
PAINT WHITE (-950 4275);
DISPLAY INVISIBLE (-950 4275);
FORCEPROP 2 LAST CDS_LOCATION R2908
J 0
(-950 4325);
DISPLAY 1.021277 (-950 4325);
DISPLAY INVISIBLE (-950 4325);
FORCEPROP 2 LAST $SEC 1
J 0
(-950 4325);
DISPLAY 0.680851 (-950 4325);
PAINT MONO (-950 4325);
DISPLAY INVISIBLE (-950 4325);
FORCEPROP 2 LAST CDS_SEC 1
J 0
(-950 4325);
DISPLAY 1.021277 (-950 4325);
DISPLAY INVISIBLE (-950 4325);
FORCEADD Q_RES..2
(-1000 3625);
FORCEPROP 1 LAST PART_NUMBER CS24702FB06
J 0
(-960 3500);
DISPLAY 0.510638 (-960 3500);
DISPLAY INVISIBLE (-960 3500);
FORCEPROP 1 LAST VALUE 4.7K
J 0
(-955 3700);
DISPLAY 0.510638 (-955 3700);
FORCEPROP 1 LAST WATTAGE 1/16W
J 0
(-960 3600);
DISPLAY 0.510638 (-960 3600);
FORCEPROP 1 LAST TOLERANCE 1%
J 0
(-955 3650);
DISPLAY 0.510638 (-955 3650);
FORCEPROP 1 LAST MATERIAL CHIP
J 0
(-960 3550);
DISPLAY 0.510638 (-960 3550);
FORCEPROP 1 LAST PACK_TYPE 0402LF
J 0
(-960 3450);
DISPLAY 0.510638 (-960 3450);
FORCEPROP 1 LAST $LOCATION R2843
J 0
(-955 3750);
DISPLAY 0.638298 (-955 3750);
FORCEPROP 1 LASTPIN (-1000 3725) $PN 1
J 0
(-995 3687);
DISPLAY 0.787234 (-995 3687);
PAINT MONO (-995 3687);
FORCEPROP 1 LASTPIN (-1000 3525) $PN 2
J 0
(-995 3535);
DISPLAY 0.787234 (-995 3535);
PAINT MONO (-995 3535);
FORCEPROP 2 LAST CDS_LIB pure_quanta
J 0
(-1000 3625);
DISPLAY INVISIBLE (-1000 3625);
FORCEPROP 1 LAST PATH I162
J 0
(-950 3800);
DISPLAY 0.978723 (-950 3800);
PAINT WHITE (-950 3800);
DISPLAY INVISIBLE (-950 3800);
FORCEPROP 0 LAST CDS_LOCATION R2843
J 0
(-950 3800);
DISPLAY 1.021277 (-950 3800);
DISPLAY INVISIBLE (-950 3800);
FORCEPROP 0 LAST $SEC 1
J 0
(-950 3800);
DISPLAY 0.680851 (-950 3800);
PAINT MONO (-950 3800);
DISPLAY INVISIBLE (-950 3800);
FORCEPROP 0 LAST CDS_SEC 1
J 0
(-950 3800);
DISPLAY 1.021277 (-950 3800);
DISPLAY INVISIBLE (-950 3800);
FORCEADD Q_RES..2
(-1000 2400);
FORCEPROP 1 LAST PART_NUMBER CS29092FB05
J 0
(-955 2275);
DISPLAY 0.510638 (-955 2275);
DISPLAY INVISIBLE (-955 2275);
FORCEPROP 1 LAST MATERIAL CHIP
J 0
(-955 2325);
DISPLAY 0.510638 (-955 2325);
FORCEPROP 1 LAST TOLERANCE 1%
J 0
(-950 2425);
DISPLAY 0.510638 (-950 2425);
FORCEPROP 1 LAST VALUE 9.09K
J 0
(-950 2475);
DISPLAY 0.510638 (-950 2475);
FORCEPROP 1 LAST PACK_TYPE 0402LF
J 0
(-945 2225);
DISPLAY 0.510638 (-945 2225);
FORCEPROP 1 LAST WATTAGE 1/16W
J 0
(-955 2375);
DISPLAY 0.510638 (-955 2375);
FORCEPROP 1 LAST $LOCATION R1791
J 0
(-950 2525);
DISPLAY 0.510638 (-950 2525);
FORCEPROP 1 LASTPIN (-1000 2500) $PN 1
J 0
(-995 2462);
DISPLAY 0.787234 (-995 2462);
PAINT MONO (-995 2462);
FORCEPROP 1 LASTPIN (-1000 2300) $PN 2
J 0
(-995 2310);
DISPLAY 0.787234 (-995 2310);
PAINT MONO (-995 2310);
FORCEPROP 2 LAST CDS_LIB pure_quanta
J 0
(-1000 2400);
DISPLAY INVISIBLE (-1000 2400);
FORCEPROP 1 LAST PATH I163
J 0
(-950 2575);
DISPLAY 0.978723 (-950 2575);
PAINT WHITE (-950 2575);
DISPLAY INVISIBLE (-950 2575);
FORCEPROP 0 LAST CDS_LOCATION R1791
J 0
(-950 2550);
DISPLAY 1.021277 (-950 2550);
DISPLAY INVISIBLE (-950 2550);
FORCEPROP 2 LAST $SEC 1
J 0
(-950 2625);
DISPLAY 0.680851 (-950 2625);
PAINT MONO (-950 2625);
DISPLAY INVISIBLE (-950 2625);
FORCEPROP 0 LAST CDS_SEC 1
J 0
(-950 2550);
DISPLAY 1.021277 (-950 2550);
DISPLAY INVISIBLE (-950 2550);
FORCEADD UNIVERSAL_POWER..1
(-1000 3200);
FORCEPROP 3 LASTPIN (-1000 3150) SIG_NAME P5V\g
J 0
(-990 3160);
DISPLAY 0.659574 (-990 3160);
PAINT MONO (-990 3160);
DISPLAY INVISIBLE (-990 3160);
FORCEPROP 1 LAST HDL_POWER P5V
J 1
(-1000 3250);
DISPLAY 0.872340 (-1000 3250);
PAINT GREEN (-1000 3250);
FORCEPROP 1 LAST PATH I167
J 0
(-950 3225);
DISPLAY 0.872340 (-950 3225);
PAINT AQUA (-950 3225);
DISPLAY INVISIBLE (-950 3225);
FORCEPROP 2 LAST CDS_LIB logical_power
J 0
(-1000 3200);
DISPLAY INVISIBLE (-1000 3200);
FORCEADD Q_RES..2
(-1000 2950);
FORCEPROP 1 LAST PART_NUMBER CS31802FB04
J 0
(-960 2825);
DISPLAY 0.510638 (-960 2825);
DISPLAY INVISIBLE (-960 2825);
FORCEPROP 1 LAST VALUE 18K
J 0
(-955 3025);
DISPLAY 0.510638 (-955 3025);
FORCEPROP 1 LAST MATERIAL CHIP
J 0
(-960 2875);
DISPLAY 0.510638 (-960 2875);
FORCEPROP 1 LAST PACK_TYPE 0402LF
J 0
(-960 2775);
DISPLAY 0.510638 (-960 2775);
FORCEPROP 1 LAST TOLERANCE 1%
J 0
(-955 2975);
DISPLAY 0.510638 (-955 2975);
FORCEPROP 1 LAST WATTAGE 1/16W
J 0
(-960 2925);
DISPLAY 0.510638 (-960 2925);
FORCEPROP 1 LAST $LOCATION R3005
J 0
(-955 3075);
DISPLAY 0.638298 (-955 3075);
FORCEPROP 1 LASTPIN (-1000 3050) $PN 1
J 0
(-995 3012);
DISPLAY 0.787234 (-995 3012);
PAINT MONO (-995 3012);
FORCEPROP 1 LASTPIN (-1000 2850) $PN 2
J 0
(-995 2860);
DISPLAY 0.787234 (-995 2860);
PAINT MONO (-995 2860);
FORCEPROP 1 LAST PATH I168
J 0
(-950 3125);
DISPLAY 0.978723 (-950 3125);
PAINT WHITE (-950 3125);
DISPLAY INVISIBLE (-950 3125);
FORCEPROP 2 LAST CDS_LIB pure_quanta
J 0
(-1000 2950);
DISPLAY INVISIBLE (-1000 2950);
FORCEPROP 0 LAST CDS_LOCATION R3005
J 0
(-950 3100);
DISPLAY 1.021277 (-950 3100);
DISPLAY INVISIBLE (-950 3100);
FORCEPROP 0 LAST $SEC 1
J 0
(-950 3125);
DISPLAY 0.680851 (-950 3125);
PAINT MONO (-950 3125);
DISPLAY INVISIBLE (-950 3125);
FORCEPROP 0 LAST CDS_SEC 1
J 0
(-950 3100);
DISPLAY 1.021277 (-950 3100);
DISPLAY INVISIBLE (-950 3100);
FORCEADD UNIVERSAL_POWER..1
(-1025 1900);
FORCEPROP 3 LASTPIN (-1025 1850) SIG_NAME P12V_AUX\g
J 0
(-1015 1860);
DISPLAY 0.659574 (-1015 1860);
PAINT MONO (-1015 1860);
DISPLAY INVISIBLE (-1015 1860);
FORCEPROP 1 LAST HDL_POWER P12V_AUX
J 1
(-1025 1950);
DISPLAY 0.872340 (-1025 1950);
PAINT GREEN (-1025 1950);
FORCEPROP 1 LAST PATH I172
J 0
(-975 1925);
DISPLAY 0.872340 (-975 1925);
PAINT AQUA (-975 1925);
DISPLAY INVISIBLE (-975 1925);
FORCEPROP 2 LAST CDS_LIB logical_power
J 0
(-1025 1900);
DISPLAY INVISIBLE (-1025 1900);
FORCEADD Q_RES..2
(-1025 1650);
FORCEPROP 1 LAST PART_NUMBER CS27872FB02
J 0
(-985 1525);
DISPLAY 0.510638 (-985 1525);
DISPLAY INVISIBLE (-985 1525);
FORCEPROP 1 LAST TOLERANCE 1%
J 0
(-980 1675);
DISPLAY 0.510638 (-980 1675);
FORCEPROP 1 LAST VALUE 7.87K
J 0
(-980 1725);
DISPLAY 0.510638 (-980 1725);
FORCEPROP 1 LAST PACK_TYPE 0402LF
J 0
(-985 1475);
DISPLAY 0.510638 (-985 1475);
FORCEPROP 1 LAST MATERIAL CHIP
J 0
(-985 1575);
DISPLAY 0.510638 (-985 1575);
FORCEPROP 1 LAST WATTAGE 1/16W
J 0
(-985 1625);
DISPLAY 0.510638 (-985 1625);
FORCEPROP 1 LAST $LOCATION R1799
J 0
(-980 1775);
DISPLAY 0.510638 (-980 1775);
FORCEPROP 1 LASTPIN (-1025 1750) $PN 1
J 0
(-1020 1712);
DISPLAY 0.787234 (-1020 1712);
PAINT MONO (-1020 1712);
FORCEPROP 1 LASTPIN (-1025 1550) $PN 2
J 0
(-1020 1560);
DISPLAY 0.787234 (-1020 1560);
PAINT MONO (-1020 1560);
FORCEPROP 1 LAST PATH I173
J 0
(-975 1825);
DISPLAY 0.978723 (-975 1825);
PAINT WHITE (-975 1825);
DISPLAY INVISIBLE (-975 1825);
FORCEPROP 2 LAST CDS_LIB pure_quanta
J 0
(-1025 1650);
DISPLAY INVISIBLE (-1025 1650);
FORCEPROP 0 LAST CDS_LOCATION R1799
J 0
(-975 1825);
DISPLAY 1.021277 (-975 1825);
DISPLAY INVISIBLE (-975 1825);
FORCEPROP 2 LAST $SEC 1
J 0
(-975 1875);
DISPLAY 0.680851 (-975 1875);
PAINT MONO (-975 1875);
DISPLAY INVISIBLE (-975 1875);
FORCEPROP 0 LAST CDS_SEC 1
J 0
(-975 1825);
DISPLAY 1.021277 (-975 1825);
DISPLAY INVISIBLE (-975 1825);
FORCEADD Q_RES..2
(-1025 1200);
FORCEPROP 1 LAST PART_NUMBER CS21212FB05
J 0
(-985 1075);
DISPLAY 0.638298 (-985 1075);
DISPLAY INVISIBLE (-985 1075);
FORCEPROP 1 LAST VALUE 1.21K
J 0
(-980 1275);
DISPLAY 0.638298 (-980 1275);
FORCEPROP 1 LAST TOLERANCE 1%
J 0
(-980 1225);
DISPLAY 0.638298 (-980 1225);
FORCEPROP 1 LAST WATTAGE 1/16W
J 0
(-985 1175);
DISPLAY 0.638298 (-985 1175);
FORCEPROP 1 LAST MATERIAL CHIP
J 0
(-985 1125);
DISPLAY 0.638298 (-985 1125);
FORCEPROP 1 LAST PACK_TYPE 0402LF
J 0
(-975 1025);
DISPLAY 0.638298 (-975 1025);
FORCEPROP 1 LAST $LOCATION R1800
J 0
(-980 1325);
DISPLAY 0.638298 (-980 1325);
FORCEPROP 1 LASTPIN (-1025 1300) $PN 1
J 0
(-1020 1262);
DISPLAY 0.787234 (-1020 1262);
PAINT MONO (-1020 1262);
FORCEPROP 1 LASTPIN (-1025 1100) $PN 2
J 0
(-1020 1110);
DISPLAY 0.787234 (-1020 1110);
PAINT MONO (-1020 1110);
FORCEPROP 2 LAST CDS_LIB pure_quanta
J 0
(-1025 1200);
DISPLAY INVISIBLE (-1025 1200);
FORCEPROP 1 LAST PATH I174
J 0
(-975 1375);
DISPLAY 0.978723 (-975 1375);
PAINT WHITE (-975 1375);
DISPLAY INVISIBLE (-975 1375);
FORCEPROP 0 LAST CDS_LOCATION R1800
J 0
(-975 1375);
DISPLAY 1.021277 (-975 1375);
DISPLAY INVISIBLE (-975 1375);
FORCEPROP 2 LAST $SEC 1
J 0
(-975 1425);
DISPLAY 0.680851 (-975 1425);
PAINT MONO (-975 1425);
DISPLAY INVISIBLE (-975 1425);
FORCEPROP 0 LAST CDS_SEC 1
J 0
(-975 1375);
DISPLAY 1.021277 (-975 1375);
DISPLAY INVISIBLE (-975 1375);
FORCEADD Q_RES..1
(-300 5175);
FORCEPROP 1 LAST PART_NUMBER CS00002JB13
J 0
(-375 5125);
DISPLAY 0.319149 (-375 5125);
DISPLAY INVISIBLE (-375 5125);
FORCEPROP 1 LAST TOLERANCE 5%
J 0
(-125 5175);
DISPLAY 0.404255 (-125 5175);
FORCEPROP 1 LAST VALUE 0
J 2
(-150 5175);
DISPLAY 0.404255 (-150 5175);
FORCEPROP 1 LAST MATERIAL EMPTY
J 0
(-75 5175);
DISPLAY 0.404255 (-75 5175);
FORCEPROP 2 LAST ROOM ADC1_BOM1
J 0
(-150 5200);
DISPLAY 0.638298 (-150 5200);
FORCEPROP 1 LAST $LOCATION R3681
J 0
(-500 5175);
DISPLAY 0.510638 (-500 5175);
FORCEPROP 1 LASTPIN (-400 5175) $PN 1
J 0
(-388 5187);
DISPLAY 0.787234 (-388 5187);
PAINT MONO (-388 5187);
FORCEPROP 1 LASTPIN (-200 5175) $PN 2
J 0
(-238 5187);
DISPLAY 0.787234 (-238 5187);
PAINT MONO (-238 5187);
FORCEPROP 1 LAST PACK_TYPE 0402LF
J 0
(-50 5175);
DISPLAY 0.510638 (-50 5175);
DISPLAY INVISIBLE (-50 5175);
FORCEPROP 1 LAST WATTAGE 1/16W
J 2
(-200 5100);
DISPLAY 0.319149 (-200 5100);
DISPLAY INVISIBLE (-200 5100);
FORCEPROP 1 LAST PATH I176
J 0
(-350 5325);
DISPLAY 0.978723 (-350 5325);
PAINT WHITE (-350 5325);
DISPLAY INVISIBLE (-350 5325);
FORCEPROP 2 LAST CDS_LIB pure_quanta
J 0
(-300 5175);
DISPLAY INVISIBLE (-300 5175);
FORCEPROP 0 LAST CDS_LOCATION R3681
J 0
(-425 5225);
DISPLAY 1.021277 (-425 5225);
DISPLAY INVISIBLE (-425 5225);
FORCEPROP 0 LAST $SEC 1
J 0
(-425 5225);
DISPLAY 0.680851 (-425 5225);
PAINT MONO (-425 5225);
DISPLAY INVISIBLE (-425 5225);
FORCEPROP 0 LAST CDS_SEC 1
J 0
(-425 5225);
DISPLAY 1.021277 (-425 5225);
DISPLAY INVISIBLE (-425 5225);
FORCEADD OFFPAGE..2
(500 5175);
FORCEPROP 2 LAST $XR0 250 
J 0
(689 5175);
DISPLAY 0.638298 (689 5175);
PAINT MONO (689 5175);
FORCEPROP 2 LAST PATH I177
J 0
(675 5250);
DISPLAY 1.021277 (675 5250);
DISPLAY INVISIBLE (675 5250);
FORCEPROP 2 LAST CDS_LIB standard
J 0
(500 5175);
DISPLAY INVISIBLE (500 5175);
FORCEPROP 1 LAST COMMENT_BODY TRUE
J 0
(455 5080);
DISPLAY 0.872340 (455 5080);
PAINT GREEN (455 5080);
DISPLAY INVISIBLE (455 5080);
FORCEPROP 1 LAST OFFPAGE TRUE
J 0
(825 5050);
DISPLAY 0.872340 (825 5050);
DISPLAY INVISIBLE (825 5050);
FORCEADD OFFPAGE..2
(500 5025);
FORCEPROP 2 LAST $XR0 250 
J 0
(689 5025);
DISPLAY 0.638298 (689 5025);
PAINT MONO (689 5025);
FORCEPROP 2 LAST PATH I178
J 0
(675 5100);
DISPLAY 1.021277 (675 5100);
DISPLAY INVISIBLE (675 5100);
FORCEPROP 2 LAST CDS_LIB standard
J 0
(500 5025);
DISPLAY INVISIBLE (500 5025);
FORCEPROP 1 LAST COMMENT_BODY TRUE
J 0
(455 4930);
DISPLAY 0.872340 (455 4930);
PAINT GREEN (455 4930);
DISPLAY INVISIBLE (455 4930);
FORCEPROP 1 LAST OFFPAGE TRUE
J 0
(825 4900);
DISPLAY 0.872340 (825 4900);
DISPLAY INVISIBLE (825 4900);
FORCEADD Q_RES..1
(-300 5025);
FORCEPROP 1 LAST PART_NUMBER CS00002JB13
J 0
(-375 4975);
DISPLAY 0.319149 (-375 4975);
DISPLAY INVISIBLE (-375 4975);
FORCEPROP 1 LAST VALUE 0
J 2
(-150 5025);
DISPLAY 0.404255 (-150 5025);
FORCEPROP 1 LAST TOLERANCE 5%
J 0
(-125 5025);
DISPLAY 0.404255 (-125 5025);
FORCEPROP 2 LAST ROOM ADC1_BOM2
J 0
(-400 4950);
DISPLAY 0.638298 (-400 4950);
FORCEPROP 1 LAST MATERIAL CHIP
J 0
(-75 5025);
DISPLAY 0.404255 (-75 5025);
PAINT RED (-75 5025);
FORCEPROP 1 LAST $LOCATION R3682
J 0
(-500 5025);
DISPLAY 0.510638 (-500 5025);
FORCEPROP 1 LASTPIN (-400 5025) $PN 1
J 0
(-388 5037);
DISPLAY 0.787234 (-388 5037);
PAINT MONO (-388 5037);
FORCEPROP 1 LASTPIN (-200 5025) $PN 2
J 0
(-238 5037);
DISPLAY 0.787234 (-238 5037);
PAINT MONO (-238 5037);
FORCEPROP 1 LAST PATH I179
J 0
(-350 5175);
DISPLAY 0.978723 (-350 5175);
PAINT WHITE (-350 5175);
DISPLAY INVISIBLE (-350 5175);
FORCEPROP 1 LAST PACK_TYPE 0402LF
J 0
(-50 5025);
DISPLAY 0.510638 (-50 5025);
DISPLAY INVISIBLE (-50 5025);
FORCEPROP 1 LAST WATTAGE 1/16W
J 2
(-200 4950);
DISPLAY 0.319149 (-200 4950);
DISPLAY INVISIBLE (-200 4950);
FORCEPROP 2 LAST CDS_LIB pure_quanta
J 0
(-300 5025);
DISPLAY INVISIBLE (-300 5025);
FORCEPROP 0 LAST CDS_LOCATION R3682
J 0
(-425 5075);
DISPLAY 1.021277 (-425 5075);
DISPLAY INVISIBLE (-425 5075);
FORCEPROP 0 LAST $SEC 1
J 0
(-425 5075);
DISPLAY 0.680851 (-425 5075);
PAINT MONO (-425 5075);
DISPLAY INVISIBLE (-425 5075);
FORCEPROP 0 LAST CDS_SEC 1
J 0
(-425 5075);
DISPLAY 1.021277 (-425 5075);
DISPLAY INVISIBLE (-425 5075);
FORCEADD Q_CAP..1
(425 4775);
FORCEPROP 1 LAST PART_NUMBER CH11006JB18
J 0
(475 4625);
DISPLAY 0.510638 (475 4625);
DISPLAY INVISIBLE (475 4625);
FORCEPROP 1 LAST VOLTAGE 50V
J 0
(475 4775);
DISPLAY 0.510638 (475 4775);
FORCEPROP 1 LAST TOLERANCE 5%
J 0
(475 4725);
DISPLAY 0.510638 (475 4725);
FORCEPROP 1 LAST MATERIAL EMPTY
J 0
(475 4675);
DISPLAY 0.510638 (475 4675);
FORCEPROP 1 LAST PACK_TYPE 0402
J 0
(475 4575);
DISPLAY 0.510638 (475 4575);
FORCEPROP 1 LAST VALUE 100PF
J 0
(475 4825);
DISPLAY 0.510638 (475 4825);
FORCEPROP 2 LAST ROOM ADC1_BOM1
J 0
(475 4925);
DISPLAY 0.638298 (475 4925);
FORCEPROP 1 LAST $LOCATION C2042
J 0
(475 4875);
DISPLAY 0.510638 (475 4875);
FORCEPROP 1 LASTPIN (425 4875) $PN 1
J 0
(435 4855);
DISPLAY 0.787234 (435 4855);
PAINT MONO (435 4855);
FORCEPROP 1 LASTPIN (425 4675) $PN 2
J 0
(435 4655);
DISPLAY 0.787234 (435 4655);
PAINT MONO (435 4655);
FORCEPROP 1 LAST PATH I180
J 0
(475 4925);
DISPLAY 0.978723 (475 4925);
PAINT WHITE (475 4925);
DISPLAY INVISIBLE (475 4925);
FORCEPROP 2 LAST CDS_LIB pure_quanta
J 0
(425 4775);
DISPLAY INVISIBLE (425 4775);
FORCEPROP 0 LAST CDS_LOCATION C2042
J 0
(475 4950);
DISPLAY 1.021277 (475 4950);
DISPLAY INVISIBLE (475 4950);
FORCEPROP 2 LAST $SEC 1
J 0
(475 4975);
DISPLAY 0.680851 (475 4975);
PAINT MONO (475 4975);
DISPLAY INVISIBLE (475 4975);
FORCEPROP 0 LAST CDS_SEC 1
J 0
(475 4950);
DISPLAY 1.021277 (475 4950);
DISPLAY INVISIBLE (475 4950);
FORCEADD Q_CAP..1
R 2
(75 4775);
FORCEPROP 1 LAST PART_NUMBER CH4104K1B00
J 0
(150 4650);
DISPLAY 0.510638 (150 4650);
DISPLAY INVISIBLE (150 4650);
FORCEPROP 1 LAST PACK_TYPE 0402
J 0
(150 4600);
DISPLAY 0.510638 (150 4600);
FORCEPROP 1 LAST VOLTAGE 25V
J 0
(150 4800);
DISPLAY 0.510638 (150 4800);
FORCEPROP 1 LAST VALUE 0.1UF
J 0
(150 4850);
DISPLAY 0.510638 (150 4850);
FORCEPROP 2 LAST ROOM ADC1_BOM2
J 0
(150 4925);
DISPLAY 0.638298 (150 4925);
FORCEPROP 1 LAST TOLERANCE 10%
J 0
(150 4750);
DISPLAY 0.510638 (150 4750);
FORCEPROP 1 LAST MATERIAL X7R
J 0
(150 4700);
DISPLAY 0.510638 (150 4700);
PAINT RED (150 4700);
FORCEPROP 1 LAST $LOCATION C2047
J 0
(150 4875);
DISPLAY 0.638298 (150 4875);
FORCEPROP 1 LASTPIN (75 4875) $PN 1
J 2
(65 4855);
DISPLAY 0.787234 (65 4855);
PAINT MONO (65 4855);
FORCEPROP 1 LASTPIN (75 4675) $PN 2
J 2
(65 4655);
DISPLAY 0.787234 (65 4655);
PAINT MONO (65 4655);
FORCEPROP 1 LAST PATH I181
J 2
(25 4925);
DISPLAY 0.978723 (25 4925);
PAINT WHITE (25 4925);
DISPLAY INVISIBLE (25 4925);
FORCEPROP 2 LAST CDS_LIB pure_quanta
J 0
(75 4775);
DISPLAY INVISIBLE (75 4775);
FORCEPROP 0 LAST CDS_LOCATION C2047
J 0
(175 4925);
DISPLAY 1.021277 (175 4925);
DISPLAY INVISIBLE (175 4925);
FORCEPROP 0 LAST $SEC 1
J 0
(175 4925);
DISPLAY 0.680851 (175 4925);
PAINT MONO (175 4925);
DISPLAY INVISIBLE (175 4925);
FORCEPROP 0 LAST CDS_SEC 1
J 0
(175 4925);
DISPLAY 1.021277 (175 4925);
DISPLAY INVISIBLE (175 4925);
FORCEADD UNIVERSAL_GND..1
(425 4500);
FORCEPROP 3 LASTPIN (425 4550) SIG_NAME GND\g
J 0
(435 4560);
DISPLAY 0.659574 (435 4560);
PAINT MONO (435 4560);
DISPLAY INVISIBLE (435 4560);
FORCEPROP 2 LAST CDS_LIB logical_power
J 0
(425 4500);
DISPLAY INVISIBLE (425 4500);
FORCEPROP 1 LAST PATH I182
J 0
(500 4500);
DISPLAY 0.872340 (500 4500);
PAINT AQUA (500 4500);
DISPLAY INVISIBLE (500 4500);
FORCEPROP 1 LAST HDL_POWER GND
J 1
(450 4425);
DISPLAY 0.872340 (450 4425);
PAINT GREEN (450 4425);
DISPLAY INVISIBLE (450 4425);
FORCEADD UNIVERSAL_GND..1
(75 4500);
FORCEPROP 3 LASTPIN (75 4550) SIG_NAME GND\g
J 0
(85 4560);
DISPLAY 0.659574 (85 4560);
PAINT MONO (85 4560);
DISPLAY INVISIBLE (85 4560);
FORCEPROP 1 LAST HDL_POWER GND
J 1
(100 4425);
DISPLAY 0.872340 (100 4425);
PAINT GREEN (100 4425);
DISPLAY INVISIBLE (100 4425);
FORCEPROP 1 LAST PATH I183
J 0
(150 4500);
DISPLAY 0.872340 (150 4500);
PAINT AQUA (150 4500);
DISPLAY INVISIBLE (150 4500);
FORCEPROP 2 LAST CDS_LIB logical_power
J 0
(75 4500);
DISPLAY INVISIBLE (75 4500);
FORCEADD OFFPAGE..2
(450 2700);
FORCEPROP 2 LAST $XR0 250 
J 0
(639 2700);
DISPLAY 0.638298 (639 2700);
PAINT MONO (639 2700);
FORCEPROP 2 LAST CDS_LIB standard
J 0
(450 2700);
DISPLAY INVISIBLE (450 2700);
FORCEPROP 1 LAST COMMENT_BODY TRUE
J 0
(405 2605);
DISPLAY 0.872340 (405 2605);
PAINT GREEN (405 2605);
DISPLAY INVISIBLE (405 2605);
FORCEPROP 1 LAST OFFPAGE TRUE
J 0
(775 2575);
DISPLAY 0.872340 (775 2575);
DISPLAY INVISIBLE (775 2575);
FORCEPROP 2 LAST PATH I184
J 0
(625 2775);
DISPLAY 1.021277 (625 2775);
DISPLAY INVISIBLE (625 2775);
FORCEADD OFFPAGE..2
(450 2550);
FORCEPROP 2 LAST $XR0 250 
J 0
(639 2550);
DISPLAY 0.638298 (639 2550);
PAINT MONO (639 2550);
FORCEPROP 2 LAST CDS_LIB standard
J 0
(450 2550);
DISPLAY INVISIBLE (450 2550);
FORCEPROP 1 LAST COMMENT_BODY TRUE
J 0
(405 2455);
DISPLAY 0.872340 (405 2455);
PAINT GREEN (405 2455);
DISPLAY INVISIBLE (405 2455);
FORCEPROP 1 LAST OFFPAGE TRUE
J 0
(775 2425);
DISPLAY 0.872340 (775 2425);
DISPLAY INVISIBLE (775 2425);
FORCEPROP 2 LAST PATH I185
J 0
(625 2625);
DISPLAY 1.021277 (625 2625);
DISPLAY INVISIBLE (625 2625);
FORCEADD UNIVERSAL_GND..1
(325 2000);
FORCEPROP 3 LASTPIN (325 2050) SIG_NAME GND\g
J 0
(335 2060);
DISPLAY 0.659574 (335 2060);
PAINT MONO (335 2060);
DISPLAY INVISIBLE (335 2060);
FORCEPROP 2 LAST CDS_LIB logical_power
J 0
(325 2000);
DISPLAY INVISIBLE (325 2000);
FORCEPROP 1 LAST HDL_POWER GND
J 1
(350 1925);
DISPLAY 0.872340 (350 1925);
PAINT GREEN (350 1925);
DISPLAY INVISIBLE (350 1925);
FORCEPROP 1 LAST PATH I186
J 0
(400 2000);
DISPLAY 0.872340 (400 2000);
PAINT AQUA (400 2000);
DISPLAY INVISIBLE (400 2000);
FORCEADD Q_CAP..1
(325 2275);
FORCEPROP 1 LAST PART_NUMBER CH11006JB18
J 0
(375 2125);
DISPLAY 0.510638 (375 2125);
DISPLAY INVISIBLE (375 2125);
FORCEPROP 1 LAST VOLTAGE 50V
J 0
(375 2275);
DISPLAY 0.510638 (375 2275);
FORCEPROP 1 LAST TOLERANCE 5%
J 0
(375 2225);
DISPLAY 0.510638 (375 2225);
FORCEPROP 1 LAST VALUE 100PF
J 0
(375 2325);
DISPLAY 0.510638 (375 2325);
FORCEPROP 1 LAST MATERIAL EMPTY
J 0
(375 2175);
DISPLAY 0.510638 (375 2175);
FORCEPROP 1 LAST PACK_TYPE 0402
J 0
(375 2075);
DISPLAY 0.510638 (375 2075);
FORCEPROP 2 LAST ROOM ADC1_BOM1
J 0
(375 2400);
DISPLAY 0.638298 (375 2400);
FORCEPROP 1 LAST $LOCATION C2044
J 0
(375 2375);
DISPLAY 0.510638 (375 2375);
FORCEPROP 1 LASTPIN (325 2375) $PN 1
J 0
(335 2355);
DISPLAY 0.787234 (335 2355);
PAINT MONO (335 2355);
FORCEPROP 1 LASTPIN (325 2175) $PN 2
J 0
(335 2155);
DISPLAY 0.787234 (335 2155);
PAINT MONO (335 2155);
FORCEPROP 1 LAST PATH I187
J 0
(375 2425);
DISPLAY 0.978723 (375 2425);
PAINT WHITE (375 2425);
DISPLAY INVISIBLE (375 2425);
FORCEPROP 2 LAST CDS_LIB pure_quanta
J 0
(325 2275);
DISPLAY INVISIBLE (325 2275);
FORCEPROP 0 LAST CDS_LOCATION C2044
J 0
(375 2450);
DISPLAY 1.021277 (375 2450);
DISPLAY INVISIBLE (375 2450);
FORCEPROP 2 LAST $SEC 1
J 0
(375 2475);
DISPLAY 0.680851 (375 2475);
PAINT MONO (375 2475);
DISPLAY INVISIBLE (375 2475);
FORCEPROP 0 LAST CDS_SEC 1
J 0
(375 2450);
DISPLAY 1.021277 (375 2450);
DISPLAY INVISIBLE (375 2450);
FORCEADD Q_CAP..1
R 2
(-25 2275);
FORCEPROP 1 LAST PART_NUMBER CH4104K1B00
J 0
(25 2150);
DISPLAY 0.510638 (25 2150);
DISPLAY INVISIBLE (25 2150);
FORCEPROP 1 LAST VOLTAGE 25V
J 0
(25 2300);
DISPLAY 0.510638 (25 2300);
FORCEPROP 1 LAST MATERIAL X7R
J 0
(25 2200);
DISPLAY 0.510638 (25 2200);
PAINT RED (25 2200);
FORCEPROP 1 LAST VALUE 0.1UF
J 0
(25 2350);
DISPLAY 0.510638 (25 2350);
FORCEPROP 2 LAST ROOM ADC1_BOM2
J 0
(25 2425);
DISPLAY 0.638298 (25 2425);
FORCEPROP 1 LAST TOLERANCE 10%
J 0
(25 2250);
DISPLAY 0.510638 (25 2250);
FORCEPROP 1 LAST PACK_TYPE 0402
J 0
(25 2100);
DISPLAY 0.510638 (25 2100);
FORCEPROP 1 LAST $LOCATION C2049
J 0
(25 2375);
DISPLAY 0.638298 (25 2375);
FORCEPROP 1 LASTPIN (-25 2375) $PN 1
J 2
(-35 2355);
DISPLAY 0.787234 (-35 2355);
PAINT MONO (-35 2355);
FORCEPROP 1 LASTPIN (-25 2175) $PN 2
J 2
(-35 2155);
DISPLAY 0.787234 (-35 2155);
PAINT MONO (-35 2155);
FORCEPROP 1 LAST PATH I188
J 2
(-75 2425);
DISPLAY 0.978723 (-75 2425);
PAINT WHITE (-75 2425);
DISPLAY INVISIBLE (-75 2425);
FORCEPROP 2 LAST CDS_LIB pure_quanta
J 0
(-25 2275);
DISPLAY INVISIBLE (-25 2275);
FORCEPROP 0 LAST CDS_LOCATION C2049
J 0
(75 2425);
DISPLAY 1.021277 (75 2425);
DISPLAY INVISIBLE (75 2425);
FORCEPROP 0 LAST $SEC 1
J 0
(75 2425);
DISPLAY 0.680851 (75 2425);
PAINT MONO (75 2425);
DISPLAY INVISIBLE (75 2425);
FORCEPROP 0 LAST CDS_SEC 1
J 0
(75 2425);
DISPLAY 1.021277 (75 2425);
DISPLAY INVISIBLE (75 2425);
FORCEADD UNIVERSAL_GND..1
(-25 2000);
FORCEPROP 3 LASTPIN (-25 2050) SIG_NAME GND\g
J 0
(-15 2060);
DISPLAY 0.659574 (-15 2060);
PAINT MONO (-15 2060);
DISPLAY INVISIBLE (-15 2060);
FORCEPROP 1 LAST HDL_POWER GND
J 1
(0 1925);
DISPLAY 0.872340 (0 1925);
PAINT GREEN (0 1925);
DISPLAY INVISIBLE (0 1925);
FORCEPROP 2 LAST CDS_LIB logical_power
J 0
(-25 2000);
DISPLAY INVISIBLE (-25 2000);
FORCEPROP 1 LAST PATH I189
J 0
(50 2000);
DISPLAY 0.872340 (50 2000);
PAINT AQUA (50 2000);
DISPLAY INVISIBLE (50 2000);
FORCEADD Q_RES..1
(5525 3100);
FORCEPROP 1 LAST PART_NUMBER CS00002JB13
J 0
(5450 3050);
DISPLAY 0.319149 (5450 3050);
DISPLAY INVISIBLE (5450 3050);
FORCEPROP 1 LAST TOLERANCE 5%
J 0
(5700 3100);
DISPLAY 0.404255 (5700 3100);
FORCEPROP 1 LAST VALUE 0
J 2
(5675 3100);
DISPLAY 0.404255 (5675 3100);
FORCEPROP 1 LAST MATERIAL EMPTY
J 0
(5750 3100);
DISPLAY 0.404255 (5750 3100);
FORCEPROP 2 LAST ROOM ADC1_BOM1
J 0
(5550 2975);
DISPLAY 0.638298 (5550 2975);
FORCEPROP 1 LAST $LOCATION R1793
J 0
(5325 3100);
DISPLAY 0.510638 (5325 3100);
FORCEPROP 1 LASTPIN (5425 3100) $PN 1
J 0
(5437 3112);
DISPLAY 0.787234 (5437 3112);
PAINT MONO (5437 3112);
FORCEPROP 1 LASTPIN (5625 3100) $PN 2
J 0
(5587 3112);
DISPLAY 0.787234 (5587 3112);
PAINT MONO (5587 3112);
FORCEPROP 2 LAST CDS_LIB pure_quanta
J 0
(5525 3100);
DISPLAY INVISIBLE (5525 3100);
FORCEPROP 1 LAST PATH I19
J 0
(5475 3250);
DISPLAY 0.978723 (5475 3250);
PAINT WHITE (5475 3250);
DISPLAY INVISIBLE (5475 3250);
FORCEPROP 1 LAST PACK_TYPE 0402LF
J 0
(5775 3100);
DISPLAY 0.510638 (5775 3100);
DISPLAY INVISIBLE (5775 3100);
FORCEPROP 1 LAST WATTAGE 1/16W
J 2
(5625 3025);
DISPLAY 0.319149 (5625 3025);
DISPLAY INVISIBLE (5625 3025);
FORCEPROP 0 LAST CDS_LOCATION R1793
J 0
(5750 3125);
DISPLAY 1.021277 (5750 3125);
DISPLAY INVISIBLE (5750 3125);
FORCEPROP 0 LAST $SEC 1
J 0
(5750 3125);
DISPLAY 0.680851 (5750 3125);
PAINT MONO (5750 3125);
DISPLAY INVISIBLE (5750 3125);
FORCEPROP 0 LAST CDS_SEC 1
J 0
(5750 3125);
DISPLAY 1.021277 (5750 3125);
DISPLAY INVISIBLE (5750 3125);
FORCEADD Q_RES..1
(-375 2700);
FORCEPROP 1 LAST PART_NUMBER CS00002JB13
J 0
(-450 2650);
DISPLAY 0.319149 (-450 2650);
DISPLAY INVISIBLE (-450 2650);
FORCEPROP 1 LAST MATERIAL EMPTY
J 0
(-150 2700);
DISPLAY 0.404255 (-150 2700);
FORCEPROP 1 LAST VALUE 0
J 2
(-225 2700);
DISPLAY 0.404255 (-225 2700);
FORCEPROP 1 LAST TOLERANCE 5%
J 0
(-200 2700);
DISPLAY 0.404255 (-200 2700);
FORCEPROP 2 LAST ROOM ADC1_BOM1
J 0
(-150 2725);
DISPLAY 0.638298 (-150 2725);
FORCEPROP 1 LAST $LOCATION R3685
J 0
(-550 2700);
DISPLAY 0.510638 (-550 2700);
FORCEPROP 1 LASTPIN (-475 2700) $PN 1
J 0
(-463 2712);
DISPLAY 0.787234 (-463 2712);
PAINT MONO (-463 2712);
FORCEPROP 1 LASTPIN (-275 2700) $PN 2
J 0
(-313 2712);
DISPLAY 0.787234 (-313 2712);
PAINT MONO (-313 2712);
FORCEPROP 1 LAST PACK_TYPE 0402LF
J 0
(-125 2700);
DISPLAY 0.510638 (-125 2700);
DISPLAY INVISIBLE (-125 2700);
FORCEPROP 1 LAST WATTAGE 1/16W
J 2
(-275 2625);
DISPLAY 0.319149 (-275 2625);
DISPLAY INVISIBLE (-275 2625);
FORCEPROP 2 LAST CDS_LIB pure_quanta
J 0
(-375 2700);
DISPLAY INVISIBLE (-375 2700);
FORCEPROP 1 LAST PATH I190
J 0
(-425 2850);
DISPLAY 0.978723 (-425 2850);
PAINT WHITE (-425 2850);
DISPLAY INVISIBLE (-425 2850);
FORCEPROP 0 LAST CDS_LOCATION R3685
J 0
(-500 2750);
DISPLAY 1.021277 (-500 2750);
DISPLAY INVISIBLE (-500 2750);
FORCEPROP 0 LAST $SEC 1
J 0
(-500 2750);
DISPLAY 0.680851 (-500 2750);
PAINT MONO (-500 2750);
DISPLAY INVISIBLE (-500 2750);
FORCEPROP 0 LAST CDS_SEC 1
J 0
(-500 2750);
DISPLAY 1.021277 (-500 2750);
DISPLAY INVISIBLE (-500 2750);
FORCEADD Q_RES..1
(-375 2550);
FORCEPROP 1 LAST PART_NUMBER CS00002JB13
J 0
(-450 2500);
DISPLAY 0.319149 (-450 2500);
DISPLAY INVISIBLE (-450 2500);
FORCEPROP 1 LAST TOLERANCE 5%
J 0
(-200 2550);
DISPLAY 0.404255 (-200 2550);
FORCEPROP 1 LAST VALUE 0
J 2
(-225 2550);
DISPLAY 0.404255 (-225 2550);
FORCEPROP 1 LAST MATERIAL CHIP
J 0
(-150 2550);
DISPLAY 0.404255 (-150 2550);
PAINT RED (-150 2550);
FORCEPROP 2 LAST ROOM ADC1_BOM2
J 0
(-450 2475);
DISPLAY 0.638298 (-450 2475);
FORCEPROP 1 LAST $LOCATION R3686
J 0
(-550 2550);
DISPLAY 0.510638 (-550 2550);
FORCEPROP 1 LASTPIN (-475 2550) $PN 1
J 0
(-463 2562);
DISPLAY 0.787234 (-463 2562);
PAINT MONO (-463 2562);
FORCEPROP 1 LASTPIN (-275 2550) $PN 2
J 0
(-313 2562);
DISPLAY 0.787234 (-313 2562);
PAINT MONO (-313 2562);
FORCEPROP 1 LAST PACK_TYPE 0402LF
J 0
(-125 2550);
DISPLAY 0.510638 (-125 2550);
DISPLAY INVISIBLE (-125 2550);
FORCEPROP 1 LAST WATTAGE 1/16W
J 2
(-275 2475);
DISPLAY 0.319149 (-275 2475);
DISPLAY INVISIBLE (-275 2475);
FORCEPROP 2 LAST CDS_LIB pure_quanta
J 0
(-375 2550);
DISPLAY INVISIBLE (-375 2550);
FORCEPROP 1 LAST PATH I191
J 0
(-425 2700);
DISPLAY 0.978723 (-425 2700);
PAINT WHITE (-425 2700);
DISPLAY INVISIBLE (-425 2700);
FORCEPROP 0 LAST CDS_LOCATION R3686
J 0
(-500 2600);
DISPLAY 1.021277 (-500 2600);
DISPLAY INVISIBLE (-500 2600);
FORCEPROP 0 LAST $SEC 1
J 0
(-500 2600);
DISPLAY 0.680851 (-500 2600);
PAINT MONO (-500 2600);
DISPLAY INVISIBLE (-500 2600);
FORCEPROP 0 LAST CDS_SEC 1
J 0
(-500 2600);
DISPLAY 1.021277 (-500 2600);
DISPLAY INVISIBLE (-500 2600);
FORCEADD UNIVERSAL_GND..1
(-1000 2100);
FORCEPROP 3 LASTPIN (-1000 2150) SIG_NAME GND\g
J 0
(-990 2160);
DISPLAY 0.659574 (-990 2160);
PAINT MONO (-990 2160);
DISPLAY INVISIBLE (-990 2160);
FORCEPROP 1 LAST HDL_POWER GND
J 1
(-975 2025);
DISPLAY 0.872340 (-975 2025);
PAINT GREEN (-975 2025);
DISPLAY INVISIBLE (-975 2025);
FORCEPROP 1 LAST PATH I192
J 0
(-925 2100);
DISPLAY 0.872340 (-925 2100);
PAINT AQUA (-925 2100);
DISPLAY INVISIBLE (-925 2100);
FORCEPROP 2 LAST CDS_LIB logical_power
J 0
(-1000 2100);
DISPLAY INVISIBLE (-1000 2100);
FORCEADD OFFPAGE..2
(450 3850);
FORCEPROP 2 LAST $XR0 250 
J 0
(639 3850);
DISPLAY 0.638298 (639 3850);
PAINT MONO (639 3850);
FORCEPROP 2 LAST PATH I193
J 0
(625 3925);
DISPLAY 1.021277 (625 3925);
DISPLAY INVISIBLE (625 3925);
FORCEPROP 1 LAST OFFPAGE TRUE
J 0
(775 3725);
DISPLAY 0.872340 (775 3725);
DISPLAY INVISIBLE (775 3725);
FORCEPROP 1 LAST COMMENT_BODY TRUE
J 0
(405 3755);
DISPLAY 0.872340 (405 3755);
PAINT GREEN (405 3755);
DISPLAY INVISIBLE (405 3755);
FORCEPROP 2 LAST CDS_LIB standard
J 0
(450 3850);
DISPLAY INVISIBLE (450 3850);
FORCEADD OFFPAGE..2
(450 3700);
FORCEPROP 2 LAST $XR0 250 
J 0
(639 3700);
DISPLAY 0.638298 (639 3700);
PAINT MONO (639 3700);
FORCEPROP 2 LAST PATH I194
J 0
(625 3775);
DISPLAY 1.021277 (625 3775);
DISPLAY INVISIBLE (625 3775);
FORCEPROP 1 LAST OFFPAGE TRUE
J 0
(775 3575);
DISPLAY 0.872340 (775 3575);
DISPLAY INVISIBLE (775 3575);
FORCEPROP 1 LAST COMMENT_BODY TRUE
J 0
(405 3605);
DISPLAY 0.872340 (405 3605);
PAINT GREEN (405 3605);
DISPLAY INVISIBLE (405 3605);
FORCEPROP 2 LAST CDS_LIB standard
J 0
(450 3700);
DISPLAY INVISIBLE (450 3700);
FORCEADD UNIVERSAL_GND..1
(350 3150);
FORCEPROP 3 LASTPIN (350 3200) SIG_NAME GND\g
J 0
(360 3210);
DISPLAY 0.659574 (360 3210);
PAINT MONO (360 3210);
DISPLAY INVISIBLE (360 3210);
FORCEPROP 1 LAST PATH I195
J 0
(425 3150);
DISPLAY 0.872340 (425 3150);
PAINT AQUA (425 3150);
DISPLAY INVISIBLE (425 3150);
FORCEPROP 1 LAST HDL_POWER GND
J 1
(375 3075);
DISPLAY 0.872340 (375 3075);
PAINT GREEN (375 3075);
DISPLAY INVISIBLE (375 3075);
FORCEPROP 2 LAST CDS_LIB logical_power
J 0
(350 3150);
DISPLAY INVISIBLE (350 3150);
FORCEADD Q_CAP..1
(350 3425);
FORCEPROP 1 LAST PART_NUMBER CH11006JB18
J 0
(400 3275);
DISPLAY 0.510638 (400 3275);
DISPLAY INVISIBLE (400 3275);
FORCEPROP 1 LAST MATERIAL EMPTY
J 0
(400 3325);
DISPLAY 0.510638 (400 3325);
FORCEPROP 1 LAST VOLTAGE 50V
J 0
(400 3425);
DISPLAY 0.510638 (400 3425);
FORCEPROP 1 LAST TOLERANCE 5%
J 0
(400 3375);
DISPLAY 0.510638 (400 3375);
FORCEPROP 1 LAST PACK_TYPE 0402
J 0
(400 3225);
DISPLAY 0.510638 (400 3225);
FORCEPROP 1 LAST VALUE 100PF
J 0
(400 3475);
DISPLAY 0.510638 (400 3475);
FORCEPROP 2 LAST ROOM ADC1_BOM1
J 0
(400 3575);
DISPLAY 0.638298 (400 3575);
FORCEPROP 1 LAST $LOCATION C2043
J 0
(400 3525);
DISPLAY 0.510638 (400 3525);
FORCEPROP 1 LASTPIN (350 3525) $PN 1
J 0
(360 3505);
DISPLAY 0.787234 (360 3505);
PAINT MONO (360 3505);
FORCEPROP 1 LASTPIN (350 3325) $PN 2
J 0
(360 3305);
DISPLAY 0.787234 (360 3305);
PAINT MONO (360 3305);
FORCEPROP 2 LAST CDS_LIB pure_quanta
J 0
(350 3425);
DISPLAY INVISIBLE (350 3425);
FORCEPROP 1 LAST PATH I196
J 0
(400 3575);
DISPLAY 0.978723 (400 3575);
PAINT WHITE (400 3575);
DISPLAY INVISIBLE (400 3575);
FORCEPROP 0 LAST CDS_LOCATION C2043
J 0
(400 3600);
DISPLAY 1.021277 (400 3600);
DISPLAY INVISIBLE (400 3600);
FORCEPROP 2 LAST $SEC 1
J 0
(400 3625);
DISPLAY 0.680851 (400 3625);
PAINT MONO (400 3625);
DISPLAY INVISIBLE (400 3625);
FORCEPROP 0 LAST CDS_SEC 1
J 0
(400 3600);
DISPLAY 1.021277 (400 3600);
DISPLAY INVISIBLE (400 3600);
FORCEADD Q_CAP..1
R 2
(0 3425);
FORCEPROP 1 LAST PART_NUMBER CH4104K1B00
J 2
(300 3300);
DISPLAY 0.510638 (300 3300);
DISPLAY INVISIBLE (300 3300);
FORCEPROP 1 LAST MATERIAL X7R
J 2
(150 3350);
DISPLAY 0.510638 (150 3350);
PAINT RED (150 3350);
FORCEPROP 1 LAST VALUE 0.1UF
J 2
(175 3500);
DISPLAY 0.510638 (175 3500);
FORCEPROP 1 LAST VOLTAGE 25V
J 2
(150 3450);
DISPLAY 0.510638 (150 3450);
FORCEPROP 1 LAST TOLERANCE 10%
J 2
(150 3400);
DISPLAY 0.510638 (150 3400);
FORCEPROP 1 LAST PACK_TYPE 0402
J 2
(175 3250);
DISPLAY 0.510638 (175 3250);
FORCEPROP 2 LAST ROOM ADC1_BOM2
J 0
(50 3600);
DISPLAY 0.638298 (50 3600);
FORCEPROP 1 LAST $LOCATION C2048
J 2
(200 3550);
DISPLAY 0.638298 (200 3550);
FORCEPROP 1 LASTPIN (0 3525) $PN 1
J 2
(-10 3505);
DISPLAY 0.787234 (-10 3505);
PAINT MONO (-10 3505);
FORCEPROP 1 LASTPIN (0 3325) $PN 2
J 2
(-10 3305);
DISPLAY 0.787234 (-10 3305);
PAINT MONO (-10 3305);
FORCEPROP 2 LAST CDS_LIB pure_quanta
J 0
(0 3425);
DISPLAY INVISIBLE (0 3425);
FORCEPROP 1 LAST PATH I197
J 2
(-50 3575);
DISPLAY 0.978723 (-50 3575);
PAINT WHITE (-50 3575);
DISPLAY INVISIBLE (-50 3575);
FORCEPROP 0 LAST CDS_LOCATION C2048
J 0
(100 3575);
DISPLAY 1.021277 (100 3575);
DISPLAY INVISIBLE (100 3575);
FORCEPROP 0 LAST $SEC 1
J 0
(100 3575);
DISPLAY 0.680851 (100 3575);
PAINT MONO (100 3575);
DISPLAY INVISIBLE (100 3575);
FORCEPROP 0 LAST CDS_SEC 1
J 0
(100 3575);
DISPLAY 1.021277 (100 3575);
DISPLAY INVISIBLE (100 3575);
FORCEADD UNIVERSAL_GND..1
(0 3150);
FORCEPROP 3 LASTPIN (0 3200) SIG_NAME GND\g
J 0
(10 3210);
DISPLAY 0.659574 (10 3210);
PAINT MONO (10 3210);
DISPLAY INVISIBLE (10 3210);
FORCEPROP 1 LAST PATH I198
J 0
(75 3150);
DISPLAY 0.872340 (75 3150);
PAINT AQUA (75 3150);
DISPLAY INVISIBLE (75 3150);
FORCEPROP 2 LAST CDS_LIB logical_power
J 0
(0 3150);
DISPLAY INVISIBLE (0 3150);
FORCEPROP 1 LAST HDL_POWER GND
J 1
(25 3075);
DISPLAY 0.872340 (25 3075);
PAINT GREEN (25 3075);
DISPLAY INVISIBLE (25 3075);
FORCEADD Q_RES..1
(-375 3850);
FORCEPROP 1 LAST PART_NUMBER CS00002JB13
J 0
(-450 3800);
DISPLAY 0.319149 (-450 3800);
DISPLAY INVISIBLE (-450 3800);
FORCEPROP 1 LAST VALUE 0
J 2
(-225 3850);
DISPLAY 0.404255 (-225 3850);
FORCEPROP 1 LAST MATERIAL EMPTY
J 0
(-150 3850);
DISPLAY 0.404255 (-150 3850);
FORCEPROP 1 LAST TOLERANCE 5%
J 0
(-200 3850);
DISPLAY 0.404255 (-200 3850);
FORCEPROP 2 LAST ROOM ADC1_BOM1
J 0
(-225 3900);
DISPLAY 0.638298 (-225 3900);
FORCEPROP 1 LAST $LOCATION R3683
J 0
(-575 3850);
DISPLAY 0.510638 (-575 3850);
FORCEPROP 1 LASTPIN (-475 3850) $PN 1
J 0
(-463 3862);
DISPLAY 0.787234 (-463 3862);
PAINT MONO (-463 3862);
FORCEPROP 1 LASTPIN (-275 3850) $PN 2
J 0
(-313 3862);
DISPLAY 0.787234 (-313 3862);
PAINT MONO (-313 3862);
FORCEPROP 1 LAST PATH I199
J 0
(-425 4000);
DISPLAY 0.978723 (-425 4000);
PAINT WHITE (-425 4000);
DISPLAY INVISIBLE (-425 4000);
FORCEPROP 2 LAST CDS_LIB pure_quanta
J 0
(-375 3850);
DISPLAY INVISIBLE (-375 3850);
FORCEPROP 1 LAST WATTAGE 1/16W
J 2
(-275 3775);
DISPLAY 0.319149 (-275 3775);
DISPLAY INVISIBLE (-275 3775);
FORCEPROP 1 LAST PACK_TYPE 0402LF
J 0
(-125 3850);
DISPLAY 0.510638 (-125 3850);
DISPLAY INVISIBLE (-125 3850);
FORCEPROP 0 LAST CDS_LOCATION R3683
J 0
(-500 3900);
DISPLAY 1.021277 (-500 3900);
DISPLAY INVISIBLE (-500 3900);
FORCEPROP 0 LAST $SEC 1
J 0
(-500 3900);
DISPLAY 0.680851 (-500 3900);
PAINT MONO (-500 3900);
DISPLAY INVISIBLE (-500 3900);
FORCEPROP 0 LAST CDS_SEC 1
J 0
(-500 3900);
DISPLAY 1.021277 (-500 3900);
DISPLAY INVISIBLE (-500 3900);
FORCEADD Q_RES..1
(5525 3150);
FORCEPROP 1 LAST PART_NUMBER CS00002JB13
J 0
(5425 3025);
DISPLAY 0.404255 (5425 3025);
DISPLAY INVISIBLE (5425 3025);
FORCEPROP 1 LAST MATERIAL EMPTY
J 0
(5750 3150);
DISPLAY 0.404255 (5750 3150);
FORCEPROP 1 LAST PACK_TYPE 0402LF
J 0
(5425 3050);
DISPLAY 0.404255 (5425 3050);
FORCEPROP 1 LAST WATTAGE 1/16W
J 2
(5650 3050);
DISPLAY 0.404255 (5650 3050);
FORCEPROP 1 LAST VALUE 0
J 2
(5675 3150);
DISPLAY 0.404255 (5675 3150);
FORCEPROP 1 LAST TOLERANCE 5%
J 0
(5700 3150);
DISPLAY 0.404255 (5700 3150);
FORCEPROP 2 LAST ROOM ADC1_BOM1
J 0
(5550 3225);
DISPLAY 0.638298 (5550 3225);
FORCEPROP 1 LAST $LOCATION R1792
J 0
(5325 3150);
DISPLAY 0.510638 (5325 3150);
FORCEPROP 1 LASTPIN (5425 3150) $PN 1
J 0
(5437 3162);
DISPLAY 0.787234 (5437 3162);
PAINT MONO (5437 3162);
FORCEPROP 1 LASTPIN (5625 3150) $PN 2
J 0
(5587 3162);
DISPLAY 0.787234 (5587 3162);
PAINT MONO (5587 3162);
FORCEPROP 2 LAST CDS_LIB pure_quanta
J 0
(5525 3150);
DISPLAY INVISIBLE (5525 3150);
FORCEPROP 1 LAST PATH I20
J 0
(5475 3300);
DISPLAY 0.978723 (5475 3300);
PAINT WHITE (5475 3300);
DISPLAY INVISIBLE (5475 3300);
FORCEPROP 0 LAST CDS_LOCATION R1792
J 0
(5750 3175);
DISPLAY 1.021277 (5750 3175);
DISPLAY INVISIBLE (5750 3175);
FORCEPROP 0 LAST $SEC 1
J 0
(5750 3175);
DISPLAY 0.680851 (5750 3175);
PAINT MONO (5750 3175);
DISPLAY INVISIBLE (5750 3175);
FORCEPROP 0 LAST CDS_SEC 1
J 0
(5750 3175);
DISPLAY 1.021277 (5750 3175);
DISPLAY INVISIBLE (5750 3175);
FORCEADD Q_RES..1
(-375 3700);
FORCEPROP 1 LAST PART_NUMBER CS00002JB13
J 0
(-450 3650);
DISPLAY 0.319149 (-450 3650);
DISPLAY INVISIBLE (-450 3650);
FORCEPROP 1 LAST VALUE 0
J 2
(-225 3700);
DISPLAY 0.404255 (-225 3700);
FORCEPROP 1 LAST MATERIAL CHIP
J 0
(-150 3700);
DISPLAY 0.404255 (-150 3700);
PAINT RED (-150 3700);
FORCEPROP 1 LAST TOLERANCE 5%
J 0
(-200 3700);
DISPLAY 0.404255 (-200 3700);
FORCEPROP 2 LAST ROOM ADC1_BOM2
J 0
(-500 3625);
DISPLAY 0.638298 (-500 3625);
FORCEPROP 1 LAST $LOCATION R3684
J 0
(-575 3700);
DISPLAY 0.510638 (-575 3700);
FORCEPROP 1 LASTPIN (-475 3700) $PN 1
J 0
(-463 3712);
DISPLAY 0.787234 (-463 3712);
PAINT MONO (-463 3712);
FORCEPROP 1 LASTPIN (-275 3700) $PN 2
J 0
(-313 3712);
DISPLAY 0.787234 (-313 3712);
PAINT MONO (-313 3712);
FORCEPROP 1 LAST PATH I200
J 0
(-425 3850);
DISPLAY 0.978723 (-425 3850);
PAINT WHITE (-425 3850);
DISPLAY INVISIBLE (-425 3850);
FORCEPROP 2 LAST CDS_LIB pure_quanta
J 0
(-375 3700);
DISPLAY INVISIBLE (-375 3700);
FORCEPROP 1 LAST WATTAGE 1/16W
J 2
(-275 3625);
DISPLAY 0.319149 (-275 3625);
DISPLAY INVISIBLE (-275 3625);
FORCEPROP 1 LAST PACK_TYPE 0402LF
J 0
(-125 3700);
DISPLAY 0.510638 (-125 3700);
DISPLAY INVISIBLE (-125 3700);
FORCEPROP 0 LAST CDS_LOCATION R3684
J 0
(-500 3750);
DISPLAY 1.021277 (-500 3750);
DISPLAY INVISIBLE (-500 3750);
FORCEPROP 0 LAST $SEC 1
J 0
(-500 3750);
DISPLAY 0.680851 (-500 3750);
PAINT MONO (-500 3750);
DISPLAY INVISIBLE (-500 3750);
FORCEPROP 0 LAST CDS_SEC 1
J 0
(-500 3750);
DISPLAY 1.021277 (-500 3750);
DISPLAY INVISIBLE (-500 3750);
FORCEADD UNIVERSAL_GND..1
(-1000 3375);
FORCEPROP 3 LASTPIN (-1000 3425) SIG_NAME GND\g
J 0
(-990 3435);
DISPLAY 0.659574 (-990 3435);
PAINT MONO (-990 3435);
DISPLAY INVISIBLE (-990 3435);
FORCEPROP 1 LAST HDL_POWER GND
J 1
(-975 3300);
DISPLAY 0.872340 (-975 3300);
PAINT GREEN (-975 3300);
DISPLAY INVISIBLE (-975 3300);
FORCEPROP 1 LAST PATH I201
J 0
(-925 3375);
DISPLAY 0.872340 (-925 3375);
PAINT AQUA (-925 3375);
DISPLAY INVISIBLE (-925 3375);
FORCEPROP 2 LAST CDS_LIB logical_power
J 0
(-1000 3375);
DISPLAY INVISIBLE (-1000 3375);
FORCEADD UNIVERSAL_GND..1
(-1025 900);
FORCEPROP 3 LASTPIN (-1025 950) SIG_NAME GND\g
J 0
(-1015 960);
DISPLAY 0.659574 (-1015 960);
PAINT MONO (-1015 960);
DISPLAY INVISIBLE (-1015 960);
FORCEPROP 1 LAST HDL_POWER GND
J 1
(-1000 825);
DISPLAY 0.872340 (-1000 825);
PAINT GREEN (-1000 825);
DISPLAY INVISIBLE (-1000 825);
FORCEPROP 1 LAST PATH I202
J 0
(-950 900);
DISPLAY 0.872340 (-950 900);
PAINT AQUA (-950 900);
DISPLAY INVISIBLE (-950 900);
FORCEPROP 2 LAST CDS_LIB logical_power
J 0
(-1025 900);
DISPLAY INVISIBLE (-1025 900);
FORCEADD OFFPAGE..2
(925 1400);
FORCEPROP 2 LAST $XR0 250 
J 0
(1114 1400);
DISPLAY 0.638298 (1114 1400);
PAINT MONO (1114 1400);
FORCEPROP 2 LAST PATH I203
J 0
(1100 1475);
DISPLAY 1.021277 (1100 1475);
DISPLAY INVISIBLE (1100 1475);
FORCEPROP 1 LAST OFFPAGE TRUE
J 0
(1250 1275);
DISPLAY 0.872340 (1250 1275);
DISPLAY INVISIBLE (1250 1275);
FORCEPROP 1 LAST COMMENT_BODY TRUE
J 0
(880 1305);
DISPLAY 0.872340 (880 1305);
PAINT GREEN (880 1305);
DISPLAY INVISIBLE (880 1305);
FORCEPROP 2 LAST CDS_LIB standard
J 0
(925 1400);
DISPLAY INVISIBLE (925 1400);
FORCEADD OFFPAGE..2
(925 1250);
FORCEPROP 2 LAST $XR0 250 
J 0
(1114 1250);
DISPLAY 0.638298 (1114 1250);
PAINT MONO (1114 1250);
FORCEPROP 2 LAST PATH I204
J 0
(1100 1325);
DISPLAY 1.021277 (1100 1325);
DISPLAY INVISIBLE (1100 1325);
FORCEPROP 1 LAST OFFPAGE TRUE
J 0
(1250 1125);
DISPLAY 0.872340 (1250 1125);
DISPLAY INVISIBLE (1250 1125);
FORCEPROP 1 LAST COMMENT_BODY TRUE
J 0
(880 1155);
DISPLAY 0.872340 (880 1155);
PAINT GREEN (880 1155);
DISPLAY INVISIBLE (880 1155);
FORCEPROP 2 LAST CDS_LIB standard
J 0
(925 1250);
DISPLAY INVISIBLE (925 1250);
FORCEADD Q_CAP..1
(700 975);
FORCEPROP 1 LAST PART_NUMBER CH11006JB18
J 0
(750 825);
DISPLAY 0.510638 (750 825);
DISPLAY INVISIBLE (750 825);
FORCEPROP 2 LAST ROOM ADC1_BOM1
J 0
(750 1100);
DISPLAY 0.638298 (750 1100);
FORCEPROP 1 LAST VALUE 100PF
J 0
(750 1025);
DISPLAY 0.510638 (750 1025);
FORCEPROP 1 LAST VOLTAGE 50V
J 0
(750 975);
DISPLAY 0.510638 (750 975);
FORCEPROP 1 LAST TOLERANCE 5%
J 0
(750 925);
DISPLAY 0.510638 (750 925);
FORCEPROP 1 LAST MATERIAL EMPTY
J 0
(750 875);
DISPLAY 0.510638 (750 875);
FORCEPROP 1 LAST PACK_TYPE 0402
J 0
(750 775);
DISPLAY 0.510638 (750 775);
FORCEPROP 1 LAST $LOCATION C1344
J 0
(750 1075);
DISPLAY 0.510638 (750 1075);
FORCEPROP 1 LASTPIN (700 1075) $PN 1
J 0
(710 1055);
DISPLAY 0.787234 (710 1055);
PAINT MONO (710 1055);
FORCEPROP 1 LASTPIN (700 875) $PN 2
J 0
(710 855);
DISPLAY 0.787234 (710 855);
PAINT MONO (710 855);
FORCEPROP 2 LAST CDS_LIB pure_quanta
J 0
(700 975);
DISPLAY INVISIBLE (700 975);
FORCEPROP 1 LAST PATH I205
J 0
(750 1125);
DISPLAY 0.978723 (750 1125);
PAINT WHITE (750 1125);
DISPLAY INVISIBLE (750 1125);
FORCEPROP 0 LAST CDS_LOCATION C1344
J 0
(750 1150);
DISPLAY 1.021277 (750 1150);
DISPLAY INVISIBLE (750 1150);
FORCEPROP 2 LAST $SEC 1
J 0
(750 1175);
DISPLAY 0.680851 (750 1175);
PAINT MONO (750 1175);
DISPLAY INVISIBLE (750 1175);
FORCEPROP 0 LAST CDS_SEC 1
J 0
(750 1150);
DISPLAY 1.021277 (750 1150);
DISPLAY INVISIBLE (750 1150);
FORCEADD UNIVERSAL_GND..1
(700 700);
FORCEPROP 3 LASTPIN (700 750) SIG_NAME GND\g
J 0
(710 760);
DISPLAY 0.659574 (710 760);
PAINT MONO (710 760);
DISPLAY INVISIBLE (710 760);
FORCEPROP 1 LAST PATH I206
J 0
(775 700);
DISPLAY 0.872340 (775 700);
PAINT AQUA (775 700);
DISPLAY INVISIBLE (775 700);
FORCEPROP 1 LAST HDL_POWER GND
J 1
(725 625);
DISPLAY 0.872340 (725 625);
PAINT GREEN (725 625);
DISPLAY INVISIBLE (725 625);
FORCEPROP 2 LAST CDS_LIB logical_power
J 0
(700 700);
DISPLAY INVISIBLE (700 700);
FORCEADD Q_CAP..1
R 2
(350 975);
FORCEPROP 1 LAST PART_NUMBER CH4104K1B00
J 0
(400 825);
DISPLAY 0.510638 (400 825);
DISPLAY INVISIBLE (400 825);
FORCEPROP 1 LAST VOLTAGE 25V
J 0
(400 975);
DISPLAY 0.510638 (400 975);
FORCEPROP 1 LAST VALUE 0.1UF
J 0
(400 1025);
DISPLAY 0.510638 (400 1025);
FORCEPROP 2 LAST ROOM ADC1_BOM2
J 0
(400 1100);
DISPLAY 0.638298 (400 1100);
FORCEPROP 1 LAST MATERIAL X7R
J 0
(400 875);
DISPLAY 0.510638 (400 875);
PAINT RED (400 875);
FORCEPROP 1 LAST PACK_TYPE 0402
J 0
(400 775);
DISPLAY 0.510638 (400 775);
FORCEPROP 1 LAST TOLERANCE 10%
J 0
(400 925);
DISPLAY 0.510638 (400 925);
FORCEPROP 1 LAST $LOCATION C2046
J 0
(400 1050);
DISPLAY 0.638298 (400 1050);
FORCEPROP 1 LASTPIN (350 1075) $PN 1
J 2
(340 1055);
DISPLAY 0.787234 (340 1055);
PAINT MONO (340 1055);
FORCEPROP 1 LASTPIN (350 875) $PN 2
J 2
(340 855);
DISPLAY 0.787234 (340 855);
PAINT MONO (340 855);
FORCEPROP 2 LAST CDS_LIB pure_quanta
J 0
(350 975);
DISPLAY INVISIBLE (350 975);
FORCEPROP 1 LAST PATH I207
J 2
(300 1125);
DISPLAY 0.978723 (300 1125);
PAINT WHITE (300 1125);
DISPLAY INVISIBLE (300 1125);
FORCEPROP 0 LAST CDS_LOCATION C2046
J 0
(450 1125);
DISPLAY 1.021277 (450 1125);
DISPLAY INVISIBLE (450 1125);
FORCEPROP 0 LAST $SEC 1
J 0
(450 1125);
DISPLAY 0.680851 (450 1125);
PAINT MONO (450 1125);
DISPLAY INVISIBLE (450 1125);
FORCEPROP 0 LAST CDS_SEC 1
J 0
(450 1125);
DISPLAY 1.021277 (450 1125);
DISPLAY INVISIBLE (450 1125);
FORCEADD UNIVERSAL_GND..1
(350 700);
FORCEPROP 3 LASTPIN (350 750) SIG_NAME GND\g
J 0
(360 760);
DISPLAY 0.659574 (360 760);
PAINT MONO (360 760);
DISPLAY INVISIBLE (360 760);
FORCEPROP 1 LAST PATH I208
J 0
(425 700);
DISPLAY 0.872340 (425 700);
PAINT AQUA (425 700);
DISPLAY INVISIBLE (425 700);
FORCEPROP 2 LAST CDS_LIB logical_power
J 0
(350 700);
DISPLAY INVISIBLE (350 700);
FORCEPROP 1 LAST HDL_POWER GND
J 1
(375 625);
DISPLAY 0.872340 (375 625);
PAINT GREEN (375 625);
DISPLAY INVISIBLE (375 625);
FORCEADD Q_RES..1
(-200 1400);
FORCEPROP 1 LAST PART_NUMBER CS00002JB13
J 0
(-275 1350);
DISPLAY 0.319149 (-275 1350);
DISPLAY INVISIBLE (-275 1350);
FORCEPROP 2 LAST ROOM ADC1_BOM1
J 0
(-400 1450);
DISPLAY 0.638298 (-400 1450);
FORCEPROP 1 LAST MATERIAL EMPTY
J 0
(25 1400);
DISPLAY 0.404255 (25 1400);
FORCEPROP 1 LAST TOLERANCE 5%
J 0
(-25 1400);
DISPLAY 0.404255 (-25 1400);
FORCEPROP 1 LAST VALUE 0
J 2
(-50 1400);
DISPLAY 0.404255 (-50 1400);
FORCEPROP 1 LAST $LOCATION R3679
J 0
(-400 1400);
DISPLAY 0.638298 (-400 1400);
FORCEPROP 1 LASTPIN (-300 1400) $PN 1
J 0
(-288 1412);
DISPLAY 0.787234 (-288 1412);
PAINT MONO (-288 1412);
FORCEPROP 1 LASTPIN (-100 1400) $PN 2
J 0
(-138 1412);
DISPLAY 0.787234 (-138 1412);
PAINT MONO (-138 1412);
FORCEPROP 1 LAST PACK_TYPE 0402LF
J 0
(50 1400);
DISPLAY 0.510638 (50 1400);
DISPLAY INVISIBLE (50 1400);
FORCEPROP 1 LAST WATTAGE 1/16W
J 2
(-100 1325);
DISPLAY 0.319149 (-100 1325);
DISPLAY INVISIBLE (-100 1325);
FORCEPROP 2 LAST CDS_LIB pure_quanta
J 0
(-200 1400);
DISPLAY INVISIBLE (-200 1400);
FORCEPROP 1 LAST PATH I209
J 0
(-250 1550);
DISPLAY 0.978723 (-250 1550);
PAINT WHITE (-250 1550);
DISPLAY INVISIBLE (-250 1550);
FORCEPROP 0 LAST CDS_LOCATION R3679
J 0
(-325 1450);
DISPLAY 1.021277 (-325 1450);
DISPLAY INVISIBLE (-325 1450);
FORCEPROP 0 LAST $SEC 1
J 0
(-325 1450);
DISPLAY 0.680851 (-325 1450);
PAINT MONO (-325 1450);
DISPLAY INVISIBLE (-325 1450);
FORCEPROP 0 LAST CDS_SEC 1
J 0
(-325 1450);
DISPLAY 1.021277 (-325 1450);
DISPLAY INVISIBLE (-325 1450);
FORCEADD OFFPAGE..1
(4525 3100);
FORCEPROP 2 LAST $XR1 250 
J 0
(4123 3100);
DISPLAY 0.638298 (4123 3100);
PAINT MONO (4123 3100);
FORCEPROP 2 LAST $XR0 241 
J 0
(4243 3100);
DISPLAY 0.638298 (4243 3100);
PAINT MONO (4243 3100);
FORCEPROP 1 LAST OFFPAGE TRUE
J 0
(4850 2975);
DISPLAY 0.872340 (4850 2975);
PAINT GREEN (4850 2975);
DISPLAY INVISIBLE (4850 2975);
FORCEPROP 1 LAST COMMENT_BODY TRUE
J 0
(4650 3000);
DISPLAY 0.872340 (4650 3000);
PAINT GREEN (4650 3000);
DISPLAY INVISIBLE (4650 3000);
FORCEPROP 2 LAST PATH I21
J 0
(4225 3150);
DISPLAY 1.021277 (4225 3150);
DISPLAY INVISIBLE (4225 3150);
FORCEPROP 2 LAST CDS_LIB standard
J 0
(4525 3100);
PAINT MONO (4525 3100);
DISPLAY INVISIBLE (4525 3100);
FORCEADD Q_RES..1
(-200 1250);
FORCEPROP 1 LAST PART_NUMBER CS00002JB13
J 0
(-275 1200);
DISPLAY 0.319149 (-275 1200);
DISPLAY INVISIBLE (-275 1200);
FORCEPROP 1 LAST TOLERANCE 5%
J 0
(-25 1250);
DISPLAY 0.404255 (-25 1250);
FORCEPROP 1 LAST MATERIAL CHIP
J 0
(25 1250);
DISPLAY 0.404255 (25 1250);
PAINT RED (25 1250);
FORCEPROP 1 LAST VALUE 0
J 2
(-50 1250);
DISPLAY 0.404255 (-50 1250);
FORCEPROP 2 LAST ROOM ADC1_BOM2
J 0
(-400 1300);
DISPLAY 0.638298 (-400 1300);
FORCEPROP 1 LAST $LOCATION R3680
J 0
(-400 1250);
DISPLAY 0.638298 (-400 1250);
FORCEPROP 1 LASTPIN (-300 1250) $PN 1
J 0
(-288 1262);
DISPLAY 0.787234 (-288 1262);
PAINT MONO (-288 1262);
FORCEPROP 1 LASTPIN (-100 1250) $PN 2
J 0
(-138 1262);
DISPLAY 0.787234 (-138 1262);
PAINT MONO (-138 1262);
FORCEPROP 1 LAST PACK_TYPE 0402LF
J 0
(50 1250);
DISPLAY 0.510638 (50 1250);
DISPLAY INVISIBLE (50 1250);
FORCEPROP 1 LAST WATTAGE 1/16W
J 2
(-100 1175);
DISPLAY 0.319149 (-100 1175);
DISPLAY INVISIBLE (-100 1175);
FORCEPROP 1 LAST PATH I210
J 0
(-250 1400);
DISPLAY 0.978723 (-250 1400);
PAINT WHITE (-250 1400);
DISPLAY INVISIBLE (-250 1400);
FORCEPROP 2 LAST CDS_LIB pure_quanta
J 0
(-200 1250);
DISPLAY INVISIBLE (-200 1250);
FORCEPROP 0 LAST CDS_LOCATION R3680
J 0
(-325 1300);
DISPLAY 1.021277 (-325 1300);
DISPLAY INVISIBLE (-325 1300);
FORCEPROP 0 LAST $SEC 1
J 0
(-325 1300);
DISPLAY 0.680851 (-325 1300);
PAINT MONO (-325 1300);
DISPLAY INVISIBLE (-325 1300);
FORCEPROP 0 LAST CDS_SEC 1
J 0
(-325 1300);
DISPLAY 1.021277 (-325 1300);
DISPLAY INVISIBLE (-325 1300);
FORCEADD OFFPAGE..4
R 2
(4225 4050);
FORCEPROP 2 LAST $XR0 250 
J 0
(3973 4050);
DISPLAY 0.638298 (3973 4050);
PAINT MONO (3973 4050);
FORCEPROP 2 LAST CDS_LIB standard
J 0
(4225 4050);
DISPLAY INVISIBLE (4225 4050);
FORCEPROP 1 LAST COMMENT_BODY TRUE
J 2
(4250 3950);
DISPLAY 0.872340 (4250 3950);
PAINT GREEN (4250 3950);
DISPLAY INVISIBLE (4250 3950);
FORCEPROP 1 LAST OFFPAGE TRUE
J 2
(3900 3925);
DISPLAY 0.872340 (3900 3925);
DISPLAY INVISIBLE (3900 3925);
FORCEPROP 2 LAST PATH I214
J 0
(4275 4125);
DISPLAY 1.021277 (4275 4125);
DISPLAY INVISIBLE (4275 4125);
FORCEADD OFFPAGE..4
R 2
(5150 875);
FORCEPROP 2 LAST $XR0 250 
J 0
(4898 875);
DISPLAY 0.638298 (4898 875);
PAINT MONO (4898 875);
FORCEPROP 1 LAST COMMENT_BODY TRUE
J 2
(5175 775);
DISPLAY 0.872340 (5175 775);
PAINT GREEN (5175 775);
DISPLAY INVISIBLE (5175 775);
FORCEPROP 1 LAST OFFPAGE TRUE
J 2
(4825 750);
DISPLAY 0.872340 (4825 750);
DISPLAY INVISIBLE (4825 750);
FORCEPROP 2 LAST CDS_LIB standard
J 2
(5150 875);
DISPLAY INVISIBLE (5150 875);
FORCEPROP 2 LAST PATH I218
J 0
(4975 925);
DISPLAY 1.021277 (4975 925);
DISPLAY INVISIBLE (4975 925);
FORCEADD OFFPAGE..3
R 2
(4525 3150);
FORCEPROP 2 LAST $XR1 250 
J 0
(4125 3150);
DISPLAY 0.638298 (4125 3150);
PAINT MONO (4125 3150);
FORCEPROP 2 LAST $XR0 241 
J 0
(4245 3150);
DISPLAY 0.638298 (4245 3150);
PAINT MONO (4245 3150);
FORCEPROP 2 LAST CDS_LIB standard
J 0
(4525 3150);
PAINT MONO (4525 3150);
DISPLAY INVISIBLE (4525 3150);
FORCEPROP 1 LAST OFFPAGE TRUE
J 2
(4200 3025);
DISPLAY 0.872340 (4200 3025);
DISPLAY INVISIBLE (4200 3025);
FORCEPROP 1 LAST COMMENT_BODY TRUE
J 2
(4575 3050);
DISPLAY 0.872340 (4575 3050);
PAINT GREEN (4575 3050);
DISPLAY INVISIBLE (4575 3050);
FORCEPROP 2 LAST PATH I22
J 0
(4200 3200);
DISPLAY 1.021277 (4200 3200);
DISPLAY INVISIBLE (4200 3200);
FORCEADD UNIVERSAL_GND..1
(3350 -300);
FORCEPROP 3 LASTPIN (3350 -250) SIG_NAME GND\g
J 0
(3360 -240);
DISPLAY 0.659574 (3360 -240);
PAINT MONO (3360 -240);
DISPLAY INVISIBLE (3360 -240);
FORCEPROP 1 LAST HDL_POWER GND
J 1
(3375 -375);
DISPLAY 0.872340 (3375 -375);
PAINT GREEN (3375 -375);
DISPLAY INVISIBLE (3375 -375);
FORCEPROP 2 LAST CDS_LIB logical_power
J 0
(3350 -300);
PAINT MONO (3350 -300);
DISPLAY INVISIBLE (3350 -300);
FORCEPROP 1 LAST PATH I222
J 0
(3425 -300);
DISPLAY 0.872340 (3425 -300);
PAINT AQUA (3425 -300);
DISPLAY INVISIBLE (3425 -300);
FORCEADD Q_RES..2
(3350 -75);
FORCEPROP 1 LAST PART_NUMBER CS21002FB06
J 0
(3390 -250);
DISPLAY 0.638298 (3390 -250);
DISPLAY INVISIBLE (3390 -250);
FORCEPROP 1 LAST VALUE 1K
J 0
(3395 0);
DISPLAY 0.638298 (3395 0);
FORCEPROP 1 LAST PACK_TYPE 0402LF
J 0
(3390 -200);
DISPLAY 0.638298 (3390 -200);
FORCEPROP 1 LAST TOLERANCE 1%
J 0
(3395 -50);
DISPLAY 0.638298 (3395 -50);
FORCEPROP 1 LAST MATERIAL CHIP
J 0
(3390 -150);
DISPLAY 0.638298 (3390 -150);
FORCEPROP 1 LAST WATTAGE 1/16W
J 0
(3390 -100);
DISPLAY 0.638298 (3390 -100);
FORCEPROP 2 LAST ROOM ADC1_BOM2
J 0
(3400 100);
DISPLAY 0.404255 (3400 100);
FORCEPROP 1 LAST $LOCATION R3668
J 0
(3395 50);
DISPLAY 0.638298 (3395 50);
FORCEPROP 1 LASTPIN (3350 25) $PN 1
J 0
(3355 -13);
DISPLAY 0.787234 (3355 -13);
PAINT MONO (3355 -13);
FORCEPROP 1 LASTPIN (3350 -175) $PN 2
J 0
(3355 -165);
DISPLAY 0.787234 (3355 -165);
PAINT MONO (3355 -165);
FORCEPROP 1 LAST PATH I223
J 0
(3400 100);
DISPLAY 0.978723 (3400 100);
PAINT WHITE (3400 100);
DISPLAY INVISIBLE (3400 100);
FORCEPROP 2 LAST CDS_LIB pure_quanta
J 0
(3350 -75);
DISPLAY INVISIBLE (3350 -75);
FORCEPROP 0 LAST CDS_LOCATION R3668
J 0
(3400 100);
DISPLAY 1.021277 (3400 100);
DISPLAY INVISIBLE (3400 100);
FORCEPROP 0 LAST $SEC 1
J 0
(3400 100);
DISPLAY 0.680851 (3400 100);
PAINT MONO (3400 100);
DISPLAY INVISIBLE (3400 100);
FORCEPROP 0 LAST CDS_SEC 1
J 0
(3400 100);
DISPLAY 1.021277 (3400 100);
DISPLAY INVISIBLE (3400 100);
FORCEADD Q_RES..2
(3350 525);
FORCEPROP 1 LAST PART_NUMBER CS21002FB06
J 0
(3390 350);
DISPLAY 0.638298 (3390 350);
DISPLAY INVISIBLE (3390 350);
FORCEPROP 1 LAST TOLERANCE 1%
J 0
(3395 550);
DISPLAY 0.638298 (3395 550);
FORCEPROP 1 LAST WATTAGE 1/16W
J 0
(3390 500);
DISPLAY 0.638298 (3390 500);
FORCEPROP 1 LAST MATERIAL EMPTY
J 0
(3390 450);
DISPLAY 0.638298 (3390 450);
PAINT RED (3390 450);
FORCEPROP 1 LAST PACK_TYPE 0402LF
J 0
(3390 400);
DISPLAY 0.638298 (3390 400);
FORCEPROP 1 LAST VALUE 1K
J 0
(3395 600);
DISPLAY 0.638298 (3395 600);
FORCEPROP 1 LAST $LOCATION R3667
J 0
(3395 650);
DISPLAY 0.638298 (3395 650);
FORCEPROP 1 LASTPIN (3350 625) $PN 1
J 0
(3355 587);
DISPLAY 0.787234 (3355 587);
PAINT MONO (3355 587);
FORCEPROP 1 LASTPIN (3350 425) $PN 2
J 0
(3355 435);
DISPLAY 0.787234 (3355 435);
PAINT MONO (3355 435);
FORCEPROP 2 LAST CDS_LIB pure_quanta
J 0
(3350 525);
DISPLAY INVISIBLE (3350 525);
FORCEPROP 1 LAST PATH I224
J 0
(3400 700);
DISPLAY 0.978723 (3400 700);
PAINT WHITE (3400 700);
DISPLAY INVISIBLE (3400 700);
FORCEPROP 0 LAST CDS_LOCATION R3667
J 0
(3400 700);
DISPLAY 1.021277 (3400 700);
DISPLAY INVISIBLE (3400 700);
FORCEPROP 0 LAST $SEC 1
J 0
(3400 700);
DISPLAY 0.680851 (3400 700);
PAINT MONO (3400 700);
DISPLAY INVISIBLE (3400 700);
FORCEPROP 0 LAST CDS_SEC 1
J 0
(3400 700);
DISPLAY 1.021277 (3400 700);
DISPLAY INVISIBLE (3400 700);
FORCEADD UNIVERSAL_POWER..1
(3350 925);
FORCEPROP 3 LASTPIN (3350 875) SIG_NAME P3V3_AUX\g
J 0
(3360 885);
DISPLAY 0.659574 (3360 885);
PAINT MONO (3360 885);
DISPLAY INVISIBLE (3360 885);
FORCEPROP 1 LAST HDL_POWER P3V3_AUX
J 1
(3350 975);
DISPLAY 0.872340 (3350 975);
PAINT GREEN (3350 975);
FORCEPROP 2 LAST CDS_LIB logical_power
J 0
(3350 925);
PAINT MONO (3350 925);
DISPLAY INVISIBLE (3350 925);
FORCEPROP 1 LAST PATH I225
J 0
(3400 950);
DISPLAY 0.872340 (3400 950);
PAINT AQUA (3400 950);
DISPLAY INVISIBLE (3400 950);
FORCEADD UNIVERSAL_GND..1
(3600 -300);
FORCEPROP 3 LASTPIN (3600 -250) SIG_NAME GND\g
J 0
(3610 -240);
DISPLAY 0.659574 (3610 -240);
PAINT MONO (3610 -240);
DISPLAY INVISIBLE (3610 -240);
FORCEPROP 1 LAST HDL_POWER GND
J 1
(3625 -375);
DISPLAY 0.872340 (3625 -375);
PAINT GREEN (3625 -375);
DISPLAY INVISIBLE (3625 -375);
FORCEPROP 2 LAST CDS_LIB logical_power
J 0
(3600 -300);
PAINT MONO (3600 -300);
DISPLAY INVISIBLE (3600 -300);
FORCEPROP 1 LAST PATH I226
J 0
(3675 -300);
DISPLAY 0.872340 (3675 -300);
PAINT AQUA (3675 -300);
DISPLAY INVISIBLE (3675 -300);
FORCEADD Q_RES..2
(3600 -75);
FORCEPROP 1 LAST PART_NUMBER CS21002FB06
J 0
(3640 -250);
DISPLAY 0.638298 (3640 -250);
DISPLAY INVISIBLE (3640 -250);
FORCEPROP 1 LAST PACK_TYPE 0402LF
J 0
(3640 -200);
DISPLAY 0.638298 (3640 -200);
FORCEPROP 1 LAST MATERIAL CHIP
J 0
(3640 -150);
DISPLAY 0.638298 (3640 -150);
FORCEPROP 1 LAST WATTAGE 1/16W
J 0
(3640 -100);
DISPLAY 0.638298 (3640 -100);
FORCEPROP 1 LAST TOLERANCE 1%
J 0
(3645 -50);
DISPLAY 0.638298 (3645 -50);
FORCEPROP 1 LAST VALUE 1K
J 0
(3645 0);
DISPLAY 0.638298 (3645 0);
FORCEPROP 2 LAST ROOM ADC1_BOM2
J 0
(3650 100);
DISPLAY 0.510638 (3650 100);
FORCEPROP 1 LAST $LOCATION R3670
J 0
(3645 50);
DISPLAY 0.638298 (3645 50);
FORCEPROP 1 LASTPIN (3600 25) $PN 1
J 0
(3605 -13);
DISPLAY 0.787234 (3605 -13);
PAINT MONO (3605 -13);
FORCEPROP 1 LASTPIN (3600 -175) $PN 2
J 0
(3605 -165);
DISPLAY 0.787234 (3605 -165);
PAINT MONO (3605 -165);
FORCEPROP 1 LAST PATH I227
J 0
(3650 100);
DISPLAY 0.978723 (3650 100);
PAINT WHITE (3650 100);
DISPLAY INVISIBLE (3650 100);
FORCEPROP 2 LAST CDS_LIB pure_quanta
J 0
(3600 -75);
DISPLAY INVISIBLE (3600 -75);
FORCEPROP 0 LAST CDS_LOCATION R3670
J 0
(3650 100);
DISPLAY 1.021277 (3650 100);
DISPLAY INVISIBLE (3650 100);
FORCEPROP 0 LAST $SEC 1
J 0
(3650 100);
DISPLAY 0.680851 (3650 100);
PAINT MONO (3650 100);
DISPLAY INVISIBLE (3650 100);
FORCEPROP 0 LAST CDS_SEC 1
J 0
(3650 100);
DISPLAY 1.021277 (3650 100);
DISPLAY INVISIBLE (3650 100);
FORCEADD Q_RES..2
(3600 525);
FORCEPROP 1 LAST PART_NUMBER CS21002FB06
J 0
(3640 350);
DISPLAY 0.638298 (3640 350);
DISPLAY INVISIBLE (3640 350);
FORCEPROP 1 LAST VALUE 1K
J 0
(3645 600);
DISPLAY 0.638298 (3645 600);
FORCEPROP 1 LAST TOLERANCE 1%
J 0
(3645 550);
DISPLAY 0.638298 (3645 550);
FORCEPROP 1 LAST WATTAGE 1/16W
J 0
(3640 500);
DISPLAY 0.638298 (3640 500);
FORCEPROP 1 LAST MATERIAL EMPTY
J 0
(3640 450);
DISPLAY 0.638298 (3640 450);
PAINT RED (3640 450);
FORCEPROP 1 LAST PACK_TYPE 0402LF
J 0
(3640 400);
DISPLAY 0.638298 (3640 400);
FORCEPROP 1 LAST $LOCATION R3669
J 0
(3645 650);
DISPLAY 0.638298 (3645 650);
FORCEPROP 1 LASTPIN (3600 625) $PN 1
J 0
(3605 587);
DISPLAY 0.787234 (3605 587);
PAINT MONO (3605 587);
FORCEPROP 1 LASTPIN (3600 425) $PN 2
J 0
(3605 435);
DISPLAY 0.787234 (3605 435);
PAINT MONO (3605 435);
FORCEPROP 2 LAST CDS_LIB pure_quanta
J 0
(3600 525);
DISPLAY INVISIBLE (3600 525);
FORCEPROP 1 LAST PATH I228
J 0
(3650 700);
DISPLAY 0.978723 (3650 700);
PAINT WHITE (3650 700);
DISPLAY INVISIBLE (3650 700);
FORCEPROP 0 LAST CDS_LOCATION R3669
J 0
(3650 700);
DISPLAY 1.021277 (3650 700);
DISPLAY INVISIBLE (3650 700);
FORCEPROP 0 LAST $SEC 1
J 0
(3650 700);
DISPLAY 0.680851 (3650 700);
PAINT MONO (3650 700);
DISPLAY INVISIBLE (3650 700);
FORCEPROP 0 LAST CDS_SEC 1
J 0
(3650 700);
DISPLAY 1.021277 (3650 700);
DISPLAY INVISIBLE (3650 700);
FORCEADD OFFPAGE..2
(4475 175);
FORCEPROP 2 LAST $XR0 250 
J 0
(4664 175);
DISPLAY 0.638298 (4664 175);
PAINT MONO (4664 175);
FORCEPROP 1 LAST OFFPAGE TRUE
J 0
(4800 50);
DISPLAY 0.872340 (4800 50);
DISPLAY INVISIBLE (4800 50);
FORCEPROP 1 LAST COMMENT_BODY TRUE
J 0
(4430 80);
DISPLAY 0.872340 (4430 80);
PAINT GREEN (4430 80);
DISPLAY INVISIBLE (4430 80);
FORCEPROP 2 LAST CDS_LIB standard
J 0
(4475 175);
DISPLAY INVISIBLE (4475 175);
FORCEPROP 2 LAST PATH I229
J 0
(4675 225);
DISPLAY 1.021277 (4675 225);
DISPLAY INVISIBLE (4675 225);
FORCEADD OFFPAGE..2
(6575 3100);
FORCEPROP 2 LAST $XR0 250 
J 0
(6794 3100);
DISPLAY 0.638298 (6794 3100);
PAINT MONO (6794 3100);
FORCEPROP 1 LAST COMMENT_BODY TRUE
J 0
(6530 3005);
DISPLAY 0.872340 (6530 3005);
PAINT GREEN (6530 3005);
DISPLAY INVISIBLE (6530 3005);
FORCEPROP 1 LAST OFFPAGE TRUE
J 0
(6900 2975);
DISPLAY 0.872340 (6900 2975);
DISPLAY INVISIBLE (6900 2975);
FORCEPROP 2 LAST PATH I23
J 0
(6775 3150);
DISPLAY 1.021277 (6775 3150);
DISPLAY INVISIBLE (6775 3150);
FORCEPROP 2 LAST CDS_LIB standard
J 0
(6575 3100);
DISPLAY INVISIBLE (6575 3100);
FORCEADD OFFPAGE..2
(4475 275);
FORCEPROP 2 LAST $XR0 250 
J 0
(4664 275);
DISPLAY 0.638298 (4664 275);
PAINT MONO (4664 275);
FORCEPROP 1 LAST COMMENT_BODY TRUE
J 0
(4430 180);
DISPLAY 0.872340 (4430 180);
PAINT GREEN (4430 180);
DISPLAY INVISIBLE (4430 180);
FORCEPROP 1 LAST OFFPAGE TRUE
J 0
(4800 150);
DISPLAY 0.872340 (4800 150);
DISPLAY INVISIBLE (4800 150);
FORCEPROP 2 LAST CDS_LIB standard
J 0
(4475 275);
DISPLAY INVISIBLE (4475 275);
FORCEPROP 2 LAST PATH I230
J 0
(4675 325);
DISPLAY 1.021277 (4675 325);
DISPLAY INVISIBLE (4675 325);
FORCEADD OFFPAGE..4
R 2
(5150 1325);
FORCEPROP 2 LAST $XR0 250 
J 0
(4898 1325);
DISPLAY 0.638298 (4898 1325);
PAINT MONO (4898 1325);
FORCEPROP 2 LAST PATH I231
J 0
(4975 1375);
DISPLAY 1.021277 (4975 1375);
DISPLAY INVISIBLE (4975 1375);
FORCEPROP 2 LAST CDS_LIB standard
J 2
(5150 1325);
DISPLAY INVISIBLE (5150 1325);
FORCEPROP 1 LAST OFFPAGE TRUE
J 2
(4825 1200);
DISPLAY 0.872340 (4825 1200);
DISPLAY INVISIBLE (4825 1200);
FORCEPROP 1 LAST COMMENT_BODY TRUE
J 2
(5175 1225);
DISPLAY 0.872340 (5175 1225);
PAINT GREEN (5175 1225);
DISPLAY INVISIBLE (5175 1225);
FORCEADD OFFPAGE..4
R 2
(5150 1375);
FORCEPROP 2 LAST $XR0 250 
J 0
(4898 1375);
DISPLAY 0.638298 (4898 1375);
PAINT MONO (4898 1375);
FORCEPROP 2 LAST PATH I232
J 0
(4975 1425);
DISPLAY 1.021277 (4975 1425);
DISPLAY INVISIBLE (4975 1425);
FORCEPROP 2 LAST CDS_LIB standard
J 2
(5150 1375);
DISPLAY INVISIBLE (5150 1375);
FORCEPROP 1 LAST OFFPAGE TRUE
J 2
(4825 1250);
DISPLAY 0.872340 (4825 1250);
DISPLAY INVISIBLE (4825 1250);
FORCEPROP 1 LAST COMMENT_BODY TRUE
J 2
(5175 1275);
DISPLAY 0.872340 (5175 1275);
PAINT GREEN (5175 1275);
DISPLAY INVISIBLE (5175 1275);
FORCEADD OFFPAGE..1
(-1150 750);
FORCEPROP 2 LAST $XR0 245 
J 0
(-1402 750);
DISPLAY 0.638298 (-1402 750);
PAINT MONO (-1402 750);
FORCEPROP 2 LAST CDS_LIB standard
J 0
(-1150 750);
DISPLAY INVISIBLE (-1150 750);
FORCEPROP 1 LAST OFFPAGE TRUE
J 0
(-825 625);
DISPLAY 0.872340 (-825 625);
PAINT GREEN (-825 625);
DISPLAY INVISIBLE (-825 625);
FORCEPROP 1 LAST COMMENT_BODY TRUE
J 0
(-1025 650);
DISPLAY 0.872340 (-1025 650);
PAINT GREEN (-1025 650);
DISPLAY INVISIBLE (-1025 650);
FORCEPROP 2 LAST PATH I233
J 2
(-1325 825);
DISPLAY 1.021277 (-1325 825);
DISPLAY INVISIBLE (-1325 825);
FORCEADD OFFPAGE..2
(1600 500);
FORCEPROP 2 LAST $XR0 250 
J 0
(1789 500);
DISPLAY 0.638298 (1789 500);
PAINT MONO (1789 500);
FORCEPROP 2 LAST CDS_LIB standard
J 0
(1600 500);
DISPLAY INVISIBLE (1600 500);
FORCEPROP 1 LAST COMMENT_BODY TRUE
J 0
(1555 405);
DISPLAY 0.872340 (1555 405);
PAINT GREEN (1555 405);
DISPLAY INVISIBLE (1555 405);
FORCEPROP 1 LAST OFFPAGE TRUE
J 0
(1925 375);
DISPLAY 0.872340 (1925 375);
DISPLAY INVISIBLE (1925 375);
FORCEPROP 2 LAST PATH I234
J 0
(1775 575);
DISPLAY 1.021277 (1775 575);
DISPLAY INVISIBLE (1775 575);
FORCEADD OFFPAGE..2
(1600 350);
FORCEPROP 2 LAST $XR0 250 
J 0
(1789 350);
DISPLAY 0.638298 (1789 350);
PAINT MONO (1789 350);
FORCEPROP 2 LAST CDS_LIB standard
J 0
(1600 350);
DISPLAY INVISIBLE (1600 350);
FORCEPROP 1 LAST COMMENT_BODY TRUE
J 0
(1555 255);
DISPLAY 0.872340 (1555 255);
PAINT GREEN (1555 255);
DISPLAY INVISIBLE (1555 255);
FORCEPROP 1 LAST OFFPAGE TRUE
J 0
(1925 225);
DISPLAY 0.872340 (1925 225);
DISPLAY INVISIBLE (1925 225);
FORCEPROP 2 LAST PATH I235
J 0
(1775 425);
DISPLAY 1.021277 (1775 425);
DISPLAY INVISIBLE (1775 425);
FORCEADD Q_CAP..1
(1375 75);
FORCEPROP 1 LAST PART_NUMBER CH11006JB18
J 0
(1425 -75);
DISPLAY 0.510638 (1425 -75);
DISPLAY INVISIBLE (1425 -75);
FORCEPROP 1 LAST TOLERANCE 5%
J 0
(1425 25);
DISPLAY 0.510638 (1425 25);
FORCEPROP 1 LAST VOLTAGE 50V
J 0
(1425 75);
DISPLAY 0.510638 (1425 75);
FORCEPROP 1 LAST MATERIAL EMPTY
J 0
(1425 -25);
DISPLAY 0.510638 (1425 -25);
FORCEPROP 1 LAST PACK_TYPE 0402
J 0
(1425 -125);
DISPLAY 0.510638 (1425 -125);
FORCEPROP 1 LAST VALUE 100PF
J 0
(1425 125);
DISPLAY 0.510638 (1425 125);
FORCEPROP 2 LAST ROOM ADC1_BOM1
J 0
(1425 200);
DISPLAY 0.638298 (1425 200);
FORCEPROP 1 LAST $LOCATION C2045
J 0
(1425 175);
DISPLAY 0.510638 (1425 175);
FORCEPROP 1 LASTPIN (1375 175) $PN 1
J 0
(1385 155);
DISPLAY 0.787234 (1385 155);
PAINT MONO (1385 155);
FORCEPROP 1 LASTPIN (1375 -25) $PN 2
J 0
(1385 -45);
DISPLAY 0.787234 (1385 -45);
PAINT MONO (1385 -45);
FORCEPROP 1 LAST PATH I236
J 0
(1425 225);
DISPLAY 0.978723 (1425 225);
PAINT WHITE (1425 225);
DISPLAY INVISIBLE (1425 225);
FORCEPROP 2 LAST CDS_LIB pure_quanta
J 0
(1375 75);
DISPLAY INVISIBLE (1375 75);
FORCEPROP 0 LAST CDS_LOCATION C2045
J 0
(1425 250);
DISPLAY 1.021277 (1425 250);
DISPLAY INVISIBLE (1425 250);
FORCEPROP 2 LAST $SEC 1
J 0
(1425 275);
DISPLAY 0.680851 (1425 275);
PAINT MONO (1425 275);
DISPLAY INVISIBLE (1425 275);
FORCEPROP 0 LAST CDS_SEC 1
J 0
(1425 250);
DISPLAY 1.021277 (1425 250);
DISPLAY INVISIBLE (1425 250);
FORCEADD UNIVERSAL_GND..1
(1375 -200);
FORCEPROP 3 LASTPIN (1375 -150) SIG_NAME GND\g
J 0
(1385 -140);
DISPLAY 0.659574 (1385 -140);
PAINT MONO (1385 -140);
DISPLAY INVISIBLE (1385 -140);
FORCEPROP 2 LAST CDS_LIB logical_power
J 0
(1375 -200);
DISPLAY INVISIBLE (1375 -200);
FORCEPROP 1 LAST HDL_POWER GND
J 1
(1400 -275);
DISPLAY 0.872340 (1400 -275);
PAINT GREEN (1400 -275);
DISPLAY INVISIBLE (1400 -275);
FORCEPROP 1 LAST PATH I237
J 0
(1450 -200);
DISPLAY 0.872340 (1450 -200);
PAINT AQUA (1450 -200);
DISPLAY INVISIBLE (1450 -200);
FORCEADD Q_CAP..1
R 2
(1025 75);
FORCEPROP 1 LAST PART_NUMBER CH4104K1B00
J 0
(1075 -50);
DISPLAY 0.510638 (1075 -50);
DISPLAY INVISIBLE (1075 -50);
FORCEPROP 1 LAST MATERIAL X7R
J 0
(1075 0);
DISPLAY 0.510638 (1075 0);
FORCEPROP 1 LAST TOLERANCE 10%
J 0
(1075 50);
DISPLAY 0.510638 (1075 50);
FORCEPROP 1 LAST PACK_TYPE 0402
J 0
(1075 -100);
DISPLAY 0.510638 (1075 -100);
FORCEPROP 1 LAST VOLTAGE 25V
J 0
(1075 100);
DISPLAY 0.510638 (1075 100);
FORCEPROP 1 LAST VALUE 0.1UF
J 0
(1075 150);
DISPLAY 0.510638 (1075 150);
FORCEPROP 2 LAST ROOM ADC1_BOM2
J 0
(1075 275);
DISPLAY 0.638298 (1075 275);
FORCEPROP 1 LAST $LOCATION C2050
J 0
(1075 200);
DISPLAY 0.638298 (1075 200);
FORCEPROP 1 LASTPIN (1025 175) $PN 1
J 2
(1015 155);
DISPLAY 0.787234 (1015 155);
PAINT MONO (1015 155);
FORCEPROP 1 LASTPIN (1025 -25) $PN 2
J 2
(1015 -45);
DISPLAY 0.787234 (1015 -45);
PAINT MONO (1015 -45);
FORCEPROP 1 LAST PATH I238
J 2
(975 225);
DISPLAY 0.978723 (975 225);
PAINT WHITE (975 225);
DISPLAY INVISIBLE (975 225);
FORCEPROP 2 LAST CDS_LIB pure_quanta
J 0
(1025 75);
DISPLAY INVISIBLE (1025 75);
FORCEPROP 0 LAST CDS_LOCATION C2050
J 0
(1125 225);
DISPLAY 1.021277 (1125 225);
DISPLAY INVISIBLE (1125 225);
FORCEPROP 0 LAST $SEC 1
J 0
(1125 225);
DISPLAY 0.680851 (1125 225);
PAINT MONO (1125 225);
DISPLAY INVISIBLE (1125 225);
FORCEPROP 0 LAST CDS_SEC 1
J 0
(1125 225);
DISPLAY 1.021277 (1125 225);
DISPLAY INVISIBLE (1125 225);
FORCEADD UNIVERSAL_GND..1
(1025 -175);
FORCEPROP 3 LASTPIN (1025 -125) SIG_NAME GND\g
J 0
(1035 -115);
DISPLAY 0.659574 (1035 -115);
PAINT MONO (1035 -115);
DISPLAY INVISIBLE (1035 -115);
FORCEPROP 1 LAST HDL_POWER GND
J 1
(1050 -250);
DISPLAY 0.872340 (1050 -250);
PAINT GREEN (1050 -250);
DISPLAY INVISIBLE (1050 -250);
FORCEPROP 1 LAST PATH I239
J 0
(1100 -175);
DISPLAY 0.872340 (1100 -175);
PAINT AQUA (1100 -175);
DISPLAY INVISIBLE (1100 -175);
FORCEPROP 2 LAST CDS_LIB logical_power
J 0
(1025 -175);
DISPLAY INVISIBLE (1025 -175);
FORCEADD OFFPAGE..3
(6575 3150);
FORCEPROP 2 LAST $XR0 250 
J 0
(6789 3150);
DISPLAY 0.638298 (6789 3150);
PAINT MONO (6789 3150);
FORCEPROP 1 LAST COMMENT_BODY TRUE
J 0
(6525 3050);
DISPLAY 0.872340 (6525 3050);
PAINT GREEN (6525 3050);
DISPLAY INVISIBLE (6525 3050);
FORCEPROP 1 LAST OFFPAGE TRUE
J 0
(6900 3025);
DISPLAY 0.872340 (6900 3025);
PAINT GREEN (6900 3025);
DISPLAY INVISIBLE (6900 3025);
FORCEPROP 2 LAST CDS_LIB standard
J 0
(6575 3150);
DISPLAY INVISIBLE (6575 3150);
FORCEPROP 2 LAST PATH I24
J 0
(6975 3200);
DISPLAY 1.021277 (6975 3200);
DISPLAY INVISIBLE (6975 3200);
FORCEADD Q_RES..1
(475 500);
FORCEPROP 1 LAST PART_NUMBER CS00002JB13
J 0
(400 450);
DISPLAY 0.319149 (400 450);
DISPLAY INVISIBLE (400 450);
FORCEPROP 1 LAST VALUE 0
J 2
(625 500);
DISPLAY 0.404255 (625 500);
FORCEPROP 1 LAST TOLERANCE 5%
J 0
(650 500);
DISPLAY 0.404255 (650 500);
FORCEPROP 2 LAST ROOM ADC1_BOM1
J 0
(275 550);
DISPLAY 0.808511 (275 550);
FORCEPROP 1 LAST MATERIAL EMPTY
J 0
(700 500);
DISPLAY 0.404255 (700 500);
PAINT RED (700 500);
FORCEPROP 1 LAST $LOCATION R3687
J 0
(275 500);
DISPLAY 0.638298 (275 500);
FORCEPROP 1 LASTPIN (375 500) $PN 1
J 0
(387 512);
DISPLAY 0.787234 (387 512);
PAINT MONO (387 512);
FORCEPROP 1 LASTPIN (575 500) $PN 2
J 0
(537 512);
DISPLAY 0.787234 (537 512);
PAINT MONO (537 512);
FORCEPROP 1 LAST PATH I240
J 0
(425 650);
DISPLAY 0.978723 (425 650);
PAINT WHITE (425 650);
DISPLAY INVISIBLE (425 650);
FORCEPROP 2 LAST CDS_LIB pure_quanta
J 0
(475 500);
DISPLAY INVISIBLE (475 500);
FORCEPROP 1 LAST WATTAGE 1/16W
J 2
(575 425);
DISPLAY 0.319149 (575 425);
DISPLAY INVISIBLE (575 425);
FORCEPROP 1 LAST PACK_TYPE 0402LF
J 0
(725 500);
DISPLAY 0.510638 (725 500);
DISPLAY INVISIBLE (725 500);
FORCEPROP 0 LAST CDS_LOCATION R3687
J 0
(350 550);
DISPLAY 1.021277 (350 550);
DISPLAY INVISIBLE (350 550);
FORCEPROP 0 LAST $SEC 1
J 0
(350 550);
DISPLAY 0.680851 (350 550);
PAINT MONO (350 550);
DISPLAY INVISIBLE (350 550);
FORCEPROP 0 LAST CDS_SEC 1
J 0
(350 550);
DISPLAY 1.021277 (350 550);
DISPLAY INVISIBLE (350 550);
FORCEADD Q_RES..1
(475 350);
FORCEPROP 1 LAST PART_NUMBER CS00002JB13
J 0
(400 300);
DISPLAY 0.319149 (400 300);
DISPLAY INVISIBLE (400 300);
FORCEPROP 1 LAST MATERIAL CHIP
J 0
(700 350);
DISPLAY 0.404255 (700 350);
FORCEPROP 1 LAST TOLERANCE 5%
J 0
(650 350);
DISPLAY 0.404255 (650 350);
FORCEPROP 1 LAST VALUE 0
J 2
(625 350);
DISPLAY 0.404255 (625 350);
FORCEPROP 2 LAST ROOM ADC1_BOM2
J 0
(275 400);
DISPLAY 0.808511 (275 400);
FORCEPROP 1 LAST $LOCATION R3688
J 0
(275 350);
DISPLAY 0.638298 (275 350);
FORCEPROP 1 LASTPIN (375 350) $PN 1
J 0
(387 362);
DISPLAY 0.787234 (387 362);
PAINT MONO (387 362);
FORCEPROP 1 LASTPIN (575 350) $PN 2
J 0
(537 362);
DISPLAY 0.787234 (537 362);
PAINT MONO (537 362);
FORCEPROP 1 LAST PATH I241
J 0
(425 500);
DISPLAY 0.978723 (425 500);
PAINT WHITE (425 500);
DISPLAY INVISIBLE (425 500);
FORCEPROP 2 LAST CDS_LIB pure_quanta
J 0
(475 350);
DISPLAY INVISIBLE (475 350);
FORCEPROP 1 LAST WATTAGE 1/16W
J 2
(575 275);
DISPLAY 0.319149 (575 275);
DISPLAY INVISIBLE (575 275);
FORCEPROP 1 LAST PACK_TYPE 0402LF
J 0
(725 350);
DISPLAY 0.510638 (725 350);
DISPLAY INVISIBLE (725 350);
FORCEPROP 0 LAST CDS_LOCATION R3688
J 0
(350 400);
DISPLAY 1.021277 (350 400);
DISPLAY INVISIBLE (350 400);
FORCEPROP 0 LAST $SEC 1
J 0
(350 400);
DISPLAY 0.680851 (350 400);
PAINT MONO (350 400);
DISPLAY INVISIBLE (350 400);
FORCEPROP 0 LAST CDS_SEC 1
J 0
(350 400);
DISPLAY 1.021277 (350 400);
DISPLAY INVISIBLE (350 400);
FORCEADD OFFPAGE..4
R 2
(5150 925);
FORCEPROP 2 LAST $XR0 250 
J 0
(4898 925);
DISPLAY 0.638298 (4898 925);
PAINT MONO (4898 925);
FORCEPROP 2 LAST PATH I288
J 0
(4875 975);
DISPLAY 1.021277 (4875 975);
DISPLAY INVISIBLE (4875 975);
FORCEPROP 2 LAST CDS_LIB standard
J 2
(5150 925);
DISPLAY INVISIBLE (5150 925);
FORCEPROP 1 LAST OFFPAGE TRUE
J 2
(4825 800);
DISPLAY 0.872340 (4825 800);
DISPLAY INVISIBLE (4825 800);
FORCEPROP 1 LAST COMMENT_BODY TRUE
J 2
(5175 825);
DISPLAY 0.872340 (5175 825);
PAINT GREEN (5175 825);
DISPLAY INVISIBLE (5175 825);
FORCEADD OFFPAGE..4
R 2
(5150 975);
FORCEPROP 2 LAST $XR0 250 
J 0
(4898 975);
DISPLAY 0.638298 (4898 975);
PAINT MONO (4898 975);
FORCEPROP 2 LAST PATH I289
J 0
(4875 1025);
DISPLAY 1.021277 (4875 1025);
DISPLAY INVISIBLE (4875 1025);
FORCEPROP 1 LAST COMMENT_BODY TRUE
J 2
(5175 875);
DISPLAY 0.872340 (5175 875);
PAINT GREEN (5175 875);
DISPLAY INVISIBLE (5175 875);
FORCEPROP 1 LAST OFFPAGE TRUE
J 2
(4825 850);
DISPLAY 0.872340 (4825 850);
DISPLAY INVISIBLE (4825 850);
FORCEPROP 2 LAST CDS_LIB standard
J 2
(5150 975);
DISPLAY INVISIBLE (5150 975);
FORCEADD OFFPAGE..4
R 2
(5150 1175);
FORCEPROP 2 LAST $XR0 250 
J 0
(4898 1175);
DISPLAY 0.638298 (4898 1175);
PAINT MONO (4898 1175);
FORCEPROP 2 LAST PATH I290
J 0
(4875 1225);
DISPLAY 1.021277 (4875 1225);
DISPLAY INVISIBLE (4875 1225);
FORCEPROP 2 LAST CDS_LIB standard
J 2
(5150 1175);
DISPLAY INVISIBLE (5150 1175);
FORCEPROP 1 LAST OFFPAGE TRUE
J 2
(4825 1050);
DISPLAY 0.872340 (4825 1050);
DISPLAY INVISIBLE (4825 1050);
FORCEPROP 1 LAST COMMENT_BODY TRUE
J 2
(5175 1075);
DISPLAY 0.872340 (5175 1075);
PAINT GREEN (5175 1075);
DISPLAY INVISIBLE (5175 1075);
FORCEADD OFFPAGE..4
R 2
(5150 1125);
FORCEPROP 2 LAST $XR0 250 
J 0
(4898 1125);
DISPLAY 0.638298 (4898 1125);
PAINT MONO (4898 1125);
FORCEPROP 2 LAST PATH I291
J 0
(4875 1175);
DISPLAY 1.021277 (4875 1175);
DISPLAY INVISIBLE (4875 1175);
FORCEPROP 2 LAST CDS_LIB standard
J 2
(5150 1125);
DISPLAY INVISIBLE (5150 1125);
FORCEPROP 1 LAST OFFPAGE TRUE
J 2
(4825 1000);
DISPLAY 0.872340 (4825 1000);
DISPLAY INVISIBLE (4825 1000);
FORCEPROP 1 LAST COMMENT_BODY TRUE
J 2
(5175 1025);
DISPLAY 0.872340 (5175 1025);
PAINT GREEN (5175 1025);
DISPLAY INVISIBLE (5175 1025);
FORCEADD OFFPAGE..4
R 2
(5150 1075);
FORCEPROP 2 LAST $XR0 250 
J 0
(4898 1075);
DISPLAY 0.638298 (4898 1075);
PAINT MONO (4898 1075);
FORCEPROP 2 LAST PATH I292
J 0
(4875 1125);
DISPLAY 1.021277 (4875 1125);
DISPLAY INVISIBLE (4875 1125);
FORCEPROP 2 LAST CDS_LIB standard
J 2
(5150 1075);
DISPLAY INVISIBLE (5150 1075);
FORCEPROP 1 LAST OFFPAGE TRUE
J 2
(4825 950);
DISPLAY 0.872340 (4825 950);
DISPLAY INVISIBLE (4825 950);
FORCEPROP 1 LAST COMMENT_BODY TRUE
J 2
(5175 975);
DISPLAY 0.872340 (5175 975);
PAINT GREEN (5175 975);
DISPLAY INVISIBLE (5175 975);
FORCEADD OFFPAGE..4
R 2
(5150 1025);
FORCEPROP 2 LAST $XR0 250 
J 0
(4898 1025);
DISPLAY 0.638298 (4898 1025);
PAINT MONO (4898 1025);
FORCEPROP 2 LAST PATH I293
J 0
(4875 1075);
DISPLAY 1.021277 (4875 1075);
DISPLAY INVISIBLE (4875 1075);
FORCEPROP 2 LAST CDS_LIB standard
J 2
(5150 1025);
DISPLAY INVISIBLE (5150 1025);
FORCEPROP 1 LAST OFFPAGE TRUE
J 2
(4825 900);
DISPLAY 0.872340 (4825 900);
DISPLAY INVISIBLE (4825 900);
FORCEPROP 1 LAST COMMENT_BODY TRUE
J 2
(5175 925);
DISPLAY 0.872340 (5175 925);
PAINT GREEN (5175 925);
DISPLAY INVISIBLE (5175 925);
FORCEADD OFFPAGE..4
R 2
(4225 3750);
FORCEPROP 2 LAST $XR0 250 
J 0
(3973 3750);
DISPLAY 0.638298 (3973 3750);
PAINT MONO (3973 3750);
FORCEPROP 2 LAST PATH I294
J 0
(3975 3800);
DISPLAY 1.021277 (3975 3800);
DISPLAY INVISIBLE (3975 3800);
FORCEPROP 2 LAST CDS_LIB standard
J 0
(4225 3750);
DISPLAY INVISIBLE (4225 3750);
FORCEPROP 1 LAST COMMENT_BODY TRUE
J 2
(4250 3650);
DISPLAY 0.872340 (4250 3650);
PAINT GREEN (4250 3650);
DISPLAY INVISIBLE (4250 3650);
FORCEPROP 1 LAST OFFPAGE TRUE
J 2
(3900 3625);
DISPLAY 0.872340 (3900 3625);
DISPLAY INVISIBLE (3900 3625);
FORCEADD OFFPAGE..4
(6725 3850);
FORCEPROP 2 LAST $XR0 250 
J 0
(6911 3850);
DISPLAY 0.638298 (6911 3850);
PAINT MONO (6911 3850);
FORCEPROP 2 LAST CDS_LIB standard
J 2
(6725 3850);
DISPLAY INVISIBLE (6725 3850);
FORCEPROP 1 LAST OFFPAGE TRUE
J 0
(7050 3725);
DISPLAY 0.872340 (7050 3725);
DISPLAY INVISIBLE (7050 3725);
FORCEPROP 1 LAST COMMENT_BODY TRUE
J 0
(6700 3750);
DISPLAY 0.872340 (6700 3750);
PAINT GREEN (6700 3750);
DISPLAY INVISIBLE (6700 3750);
FORCEPROP 2 LAST PATH I295
J 2
(6975 3900);
DISPLAY 1.021277 (6975 3900);
DISPLAY INVISIBLE (6975 3900);
FORCEADD OFFPAGE..1
R 2
(6750 3950);
FORCEPROP 2 LAST $XR0 250 
J 0
(6936 3950);
DISPLAY 0.638298 (6936 3950);
PAINT MONO (6936 3950);
FORCEPROP 2 LAST PATH I297
J 0
(6950 4000);
DISPLAY 1.021277 (6950 4000);
DISPLAY INVISIBLE (6950 4000);
FORCEPROP 2 LAST CDS_LIB standard
J 2
(6750 3950);
DISPLAY INVISIBLE (6750 3950);
FORCEPROP 1 LAST OFFPAGE TRUE
J 2
(6425 3825);
DISPLAY 0.872340 (6425 3825);
PAINT GREEN (6425 3825);
DISPLAY INVISIBLE (6425 3825);
FORCEPROP 1 LAST COMMENT_BODY TRUE
J 2
(6625 3850);
DISPLAY 0.872340 (6625 3850);
PAINT GREEN (6625 3850);
DISPLAY INVISIBLE (6625 3850);
FORCEADD OFFPAGE..4
(6725 3750);
FORCEPROP 2 LAST $XR0 250 
J 0
(6911 3750);
DISPLAY 0.638298 (6911 3750);
PAINT MONO (6911 3750);
FORCEPROP 2 LAST CDS_LIB standard
J 2
(6725 3750);
DISPLAY INVISIBLE (6725 3750);
FORCEPROP 1 LAST OFFPAGE TRUE
J 0
(7050 3625);
DISPLAY 0.872340 (7050 3625);
DISPLAY INVISIBLE (7050 3625);
FORCEPROP 1 LAST COMMENT_BODY TRUE
J 0
(6700 3650);
DISPLAY 0.872340 (6700 3650);
PAINT GREEN (6700 3650);
DISPLAY INVISIBLE (6700 3650);
FORCEPROP 2 LAST PATH I298
J 2
(6975 3800);
DISPLAY 1.021277 (6975 3800);
DISPLAY INVISIBLE (6975 3800);
FORCEADD OFFPAGE..4
R 2
(4225 3950);
FORCEPROP 2 LAST $XR0 250 
J 0
(3973 3950);
DISPLAY 0.638298 (3973 3950);
PAINT MONO (3973 3950);
FORCEPROP 2 LAST PATH I299
J 0
(3975 4000);
DISPLAY 1.021277 (3975 4000);
DISPLAY INVISIBLE (3975 4000);
FORCEPROP 1 LAST OFFPAGE TRUE
J 2
(3900 3825);
DISPLAY 0.872340 (3900 3825);
DISPLAY INVISIBLE (3900 3825);
FORCEPROP 1 LAST COMMENT_BODY TRUE
J 2
(4250 3850);
DISPLAY 0.872340 (4250 3850);
PAINT GREEN (4250 3850);
DISPLAY INVISIBLE (4250 3850);
FORCEPROP 2 LAST CDS_LIB standard
J 0
(4225 3950);
DISPLAY INVISIBLE (4225 3950);
FORCEADD OFFPAGE..4
R 2
(4225 3850);
FORCEPROP 2 LAST $XR0 250 
J 0
(3973 3850);
DISPLAY 0.638298 (3973 3850);
PAINT MONO (3973 3850);
FORCEPROP 2 LAST PATH I300
J 0
(3975 3900);
DISPLAY 1.021277 (3975 3900);
DISPLAY INVISIBLE (3975 3900);
FORCEPROP 2 LAST CDS_LIB standard
J 0
(4225 3850);
DISPLAY INVISIBLE (4225 3850);
FORCEPROP 1 LAST COMMENT_BODY TRUE
J 2
(4250 3750);
DISPLAY 0.872340 (4250 3750);
PAINT GREEN (4250 3750);
DISPLAY INVISIBLE (4250 3750);
FORCEPROP 1 LAST OFFPAGE TRUE
J 2
(3900 3725);
DISPLAY 0.872340 (3900 3725);
DISPLAY INVISIBLE (3900 3725);
FORCEADD OFFPAGE..2
(3225 5200);
FORCEPROP 2 LAST $XR0 250 
J 0
(3414 5200);
DISPLAY 0.638298 (3414 5200);
PAINT MONO (3414 5200);
FORCEPROP 2 LAST PATH I301
J 0
(3425 5250);
DISPLAY 1.021277 (3425 5250);
DISPLAY INVISIBLE (3425 5250);
FORCEPROP 2 LAST CDS_LIB standard
J 0
(3225 5200);
DISPLAY INVISIBLE (3225 5200);
FORCEPROP 1 LAST COMMENT_BODY TRUE
J 0
(3180 5105);
DISPLAY 0.872340 (3180 5105);
PAINT GREEN (3180 5105);
DISPLAY INVISIBLE (3180 5105);
FORCEPROP 1 LAST OFFPAGE TRUE
J 0
(3550 5075);
DISPLAY 0.872340 (3550 5075);
DISPLAY INVISIBLE (3550 5075);
FORCEADD OFFPAGE..2
(3225 4700);
FORCEPROP 2 LAST $XR0 250 
J 0
(3414 4700);
DISPLAY 0.638298 (3414 4700);
PAINT MONO (3414 4700);
FORCEPROP 2 LAST PATH I302
J 0
(3425 4750);
DISPLAY 1.021277 (3425 4750);
DISPLAY INVISIBLE (3425 4750);
FORCEPROP 1 LAST OFFPAGE TRUE
J 0
(3550 4575);
DISPLAY 0.872340 (3550 4575);
DISPLAY INVISIBLE (3550 4575);
FORCEPROP 1 LAST COMMENT_BODY TRUE
J 0
(3180 4605);
DISPLAY 0.872340 (3180 4605);
PAINT GREEN (3180 4605);
DISPLAY INVISIBLE (3180 4605);
FORCEPROP 2 LAST CDS_LIB standard
J 0
(3225 4700);
DISPLAY INVISIBLE (3225 4700);
FORCEADD UNIVERSAL_GND..1
(2975 4850);
FORCEPROP 3 LASTPIN (2975 4900) SIG_NAME GND\g
J 0
(2985 4910);
DISPLAY 0.659574 (2985 4910);
PAINT MONO (2985 4910);
DISPLAY INVISIBLE (2985 4910);
FORCEPROP 1 LAST PATH I303
J 0
(3050 4850);
DISPLAY 0.872340 (3050 4850);
PAINT AQUA (3050 4850);
DISPLAY INVISIBLE (3050 4850);
FORCEPROP 2 LAST CDS_LIB logical_power
J 0
(2975 4850);
DISPLAY INVISIBLE (2975 4850);
FORCEPROP 1 LAST HDL_POWER GND
J 1
(3000 4775);
DISPLAY 0.872340 (3000 4775);
PAINT GREEN (3000 4775);
DISPLAY INVISIBLE (3000 4775);
FORCEADD Q_CAP..1
(2975 5050);
FORCEPROP 1 LAST PART_NUMBER CH11006JB18
J 0
(3025 4900);
DISPLAY 0.510638 (3025 4900);
DISPLAY INVISIBLE (3025 4900);
FORCEPROP 1 LAST VALUE 100PF
J 0
(3025 5100);
DISPLAY 0.510638 (3025 5100);
FORCEPROP 1 LAST MATERIAL EMPTY
J 0
(3025 4950);
DISPLAY 0.510638 (3025 4950);
FORCEPROP 1 LAST VOLTAGE 50V
J 0
(3025 5050);
DISPLAY 0.510638 (3025 5050);
FORCEPROP 1 LAST PACK_TYPE 0402
J 0
(3025 4850);
DISPLAY 0.510638 (3025 4850);
FORCEPROP 2 LAST ROOM ADC1_BOM1
J 0
(3150 5025);
DISPLAY 0.638298 (3150 5025);
FORCEPROP 1 LAST TOLERANCE 5%
J 0
(3025 5000);
DISPLAY 0.510638 (3025 5000);
FORCEPROP 1 LAST $LOCATION C2176
J 0
(3025 5150);
DISPLAY 0.510638 (3025 5150);
FORCEPROP 1 LASTPIN (2975 5150) $PN 1
J 0
(2985 5130);
DISPLAY 0.787234 (2985 5130);
PAINT MONO (2985 5130);
FORCEPROP 1 LASTPIN (2975 4950) $PN 2
J 0
(2985 4930);
DISPLAY 0.787234 (2985 4930);
PAINT MONO (2985 4930);
FORCEPROP 1 LAST PATH I304
J 0
(3025 5200);
DISPLAY 0.978723 (3025 5200);
PAINT WHITE (3025 5200);
DISPLAY INVISIBLE (3025 5200);
FORCEPROP 2 LAST CDS_LIB pure_quanta
J 0
(2975 5050);
DISPLAY INVISIBLE (2975 5050);
FORCEPROP 0 LAST CDS_LOCATION C2176
J 0
(3025 5225);
DISPLAY 1.021277 (3025 5225);
DISPLAY INVISIBLE (3025 5225);
FORCEPROP 2 LAST $SEC 1
J 0
(3025 5250);
DISPLAY 0.680851 (3025 5250);
PAINT MONO (3025 5250);
DISPLAY INVISIBLE (3025 5250);
FORCEPROP 0 LAST CDS_SEC 1
J 0
(3025 5225);
DISPLAY 1.021277 (3025 5225);
DISPLAY INVISIBLE (3025 5225);
FORCEADD Q_CAP..1
R 2
(2950 4525);
FORCEPROP 1 LAST PART_NUMBER CH4104K1B00
J 2
(3250 4400);
DISPLAY 0.510638 (3250 4400);
DISPLAY INVISIBLE (3250 4400);
FORCEPROP 1 LAST VOLTAGE 25V
J 2
(3100 4550);
DISPLAY 0.510638 (3100 4550);
FORCEPROP 1 LAST VALUE 0.1UF
J 2
(3125 4600);
DISPLAY 0.510638 (3125 4600);
FORCEPROP 1 LAST MATERIAL X7R
J 2
(3100 4450);
DISPLAY 0.510638 (3100 4450);
PAINT RED (3100 4450);
FORCEPROP 1 LAST TOLERANCE 10%
J 2
(3100 4500);
DISPLAY 0.510638 (3100 4500);
FORCEPROP 2 LAST ROOM ADC1_BOM2
J 0
(3150 4550);
DISPLAY 0.638298 (3150 4550);
FORCEPROP 1 LAST PACK_TYPE 0402
J 2
(3125 4350);
DISPLAY 0.510638 (3125 4350);
FORCEPROP 1 LAST $LOCATION C2178
J 2
(3150 4650);
DISPLAY 0.787234 (3150 4650);
FORCEPROP 1 LASTPIN (2950 4625) $PN 1
J 2
(2940 4605);
DISPLAY 0.787234 (2940 4605);
PAINT MONO (2940 4605);
FORCEPROP 1 LASTPIN (2950 4425) $PN 2
J 2
(2940 4405);
DISPLAY 0.787234 (2940 4405);
PAINT MONO (2940 4405);
FORCEPROP 1 LAST PATH I305
J 2
(2900 4675);
DISPLAY 0.978723 (2900 4675);
PAINT WHITE (2900 4675);
DISPLAY INVISIBLE (2900 4675);
FORCEPROP 2 LAST CDS_LIB pure_quanta
J 0
(2950 4525);
DISPLAY INVISIBLE (2950 4525);
FORCEPROP 0 LAST CDS_LOCATION C2178
J 0
(2900 4675);
DISPLAY 1.021277 (2900 4675);
DISPLAY INVISIBLE (2900 4675);
FORCEPROP 0 LAST $SEC 1
J 0
(2900 4675);
DISPLAY 0.680851 (2900 4675);
PAINT MONO (2900 4675);
DISPLAY INVISIBLE (2900 4675);
FORCEPROP 0 LAST CDS_SEC 1
J 0
(2900 4675);
DISPLAY 1.021277 (2900 4675);
DISPLAY INVISIBLE (2900 4675);
FORCEADD UNIVERSAL_GND..1
(2950 4350);
FORCEPROP 3 LASTPIN (2950 4400) SIG_NAME GND\g
J 0
(2960 4410);
DISPLAY 0.659574 (2960 4410);
PAINT MONO (2960 4410);
DISPLAY INVISIBLE (2960 4410);
FORCEPROP 1 LAST PATH I306
J 0
(3025 4350);
DISPLAY 0.872340 (3025 4350);
PAINT AQUA (3025 4350);
DISPLAY INVISIBLE (3025 4350);
FORCEPROP 1 LAST HDL_POWER GND
J 1
(2975 4275);
DISPLAY 0.872340 (2975 4275);
PAINT GREEN (2975 4275);
DISPLAY INVISIBLE (2975 4275);
FORCEPROP 2 LAST CDS_LIB logical_power
J 0
(2950 4350);
DISPLAY INVISIBLE (2950 4350);
FORCEADD OFFPAGE..2
(3200 4225);
FORCEPROP 2 LAST $XR0 250 
J 0
(3389 4225);
DISPLAY 0.638298 (3389 4225);
PAINT MONO (3389 4225);
FORCEPROP 2 LAST PATH I307
J 0
(3400 4275);
DISPLAY 1.021277 (3400 4275);
DISPLAY INVISIBLE (3400 4275);
FORCEPROP 1 LAST OFFPAGE TRUE
J 0
(3525 4100);
DISPLAY 0.872340 (3525 4100);
DISPLAY INVISIBLE (3525 4100);
FORCEPROP 1 LAST COMMENT_BODY TRUE
J 0
(3155 4130);
DISPLAY 0.872340 (3155 4130);
PAINT GREEN (3155 4130);
DISPLAY INVISIBLE (3155 4130);
FORCEPROP 2 LAST CDS_LIB standard
J 0
(3200 4225);
DISPLAY INVISIBLE (3200 4225);
FORCEADD OFFPAGE..2
(3200 3725);
FORCEPROP 2 LAST $XR0 250 
J 0
(3389 3725);
DISPLAY 0.638298 (3389 3725);
PAINT MONO (3389 3725);
FORCEPROP 2 LAST PATH I308
J 0
(3400 3775);
DISPLAY 1.021277 (3400 3775);
DISPLAY INVISIBLE (3400 3775);
FORCEPROP 2 LAST CDS_LIB standard
J 0
(3200 3725);
DISPLAY INVISIBLE (3200 3725);
FORCEPROP 1 LAST COMMENT_BODY TRUE
J 0
(3155 3630);
DISPLAY 0.872340 (3155 3630);
PAINT GREEN (3155 3630);
DISPLAY INVISIBLE (3155 3630);
FORCEPROP 1 LAST OFFPAGE TRUE
J 0
(3525 3600);
DISPLAY 0.872340 (3525 3600);
DISPLAY INVISIBLE (3525 3600);
FORCEADD Q_CAP..1
(2950 4075);
FORCEPROP 1 LAST PART_NUMBER CH11006JB18
J 0
(3000 3925);
DISPLAY 0.510638 (3000 3925);
DISPLAY INVISIBLE (3000 3925);
FORCEPROP 1 LAST VOLTAGE 50V
J 0
(3000 4075);
DISPLAY 0.510638 (3000 4075);
FORCEPROP 1 LAST TOLERANCE 5%
J 0
(3000 4025);
DISPLAY 0.510638 (3000 4025);
FORCEPROP 1 LAST VALUE 100PF
J 0
(3000 4125);
DISPLAY 0.510638 (3000 4125);
FORCEPROP 1 LAST MATERIAL EMPTY
J 0
(3000 3975);
DISPLAY 0.510638 (3000 3975);
FORCEPROP 2 LAST ROOM ADC1_BOM1
J 0
(3075 4025);
DISPLAY 0.638298 (3075 4025);
FORCEPROP 1 LAST PACK_TYPE 0402
J 0
(3000 3875);
DISPLAY 0.510638 (3000 3875);
FORCEPROP 1 LAST $LOCATION C2175
J 0
(3000 4175);
DISPLAY 0.510638 (3000 4175);
FORCEPROP 1 LASTPIN (2950 4175) $PN 1
J 0
(2960 4155);
DISPLAY 0.787234 (2960 4155);
PAINT MONO (2960 4155);
FORCEPROP 1 LASTPIN (2950 3975) $PN 2
J 0
(2960 3955);
DISPLAY 0.787234 (2960 3955);
PAINT MONO (2960 3955);
FORCEPROP 1 LAST PATH I309
J 0
(3000 4225);
DISPLAY 0.978723 (3000 4225);
PAINT WHITE (3000 4225);
DISPLAY INVISIBLE (3000 4225);
FORCEPROP 2 LAST CDS_LIB pure_quanta
J 0
(2950 4075);
DISPLAY INVISIBLE (2950 4075);
FORCEPROP 0 LAST CDS_LOCATION C2175
J 0
(3000 4250);
DISPLAY 1.021277 (3000 4250);
DISPLAY INVISIBLE (3000 4250);
FORCEPROP 2 LAST $SEC 1
J 0
(3000 4275);
DISPLAY 0.680851 (3000 4275);
PAINT MONO (3000 4275);
DISPLAY INVISIBLE (3000 4275);
FORCEPROP 0 LAST CDS_SEC 1
J 0
(3000 4250);
DISPLAY 1.021277 (3000 4250);
DISPLAY INVISIBLE (3000 4250);
FORCEADD UNIVERSAL_GND..1
(2950 3875);
FORCEPROP 3 LASTPIN (2950 3925) SIG_NAME GND\g
J 0
(2960 3935);
DISPLAY 0.659574 (2960 3935);
PAINT MONO (2960 3935);
DISPLAY INVISIBLE (2960 3935);
FORCEPROP 1 LAST PATH I310
J 0
(3025 3875);
DISPLAY 0.872340 (3025 3875);
PAINT AQUA (3025 3875);
DISPLAY INVISIBLE (3025 3875);
FORCEPROP 1 LAST HDL_POWER GND
J 1
(2975 3800);
DISPLAY 0.872340 (2975 3800);
PAINT GREEN (2975 3800);
DISPLAY INVISIBLE (2975 3800);
FORCEPROP 2 LAST CDS_LIB logical_power
J 0
(2950 3875);
DISPLAY INVISIBLE (2950 3875);
FORCEADD Q_CAP..1
R 2
(2925 3550);
FORCEPROP 1 LAST PART_NUMBER CH4104K1B00
J 2
(3225 3425);
DISPLAY 0.510638 (3225 3425);
DISPLAY INVISIBLE (3225 3425);
FORCEPROP 1 LAST VOLTAGE 25V
J 2
(3075 3575);
DISPLAY 0.510638 (3075 3575);
FORCEPROP 1 LAST PACK_TYPE 0402
J 2
(3100 3375);
DISPLAY 0.510638 (3100 3375);
FORCEPROP 1 LAST MATERIAL X7R
J 2
(3075 3475);
DISPLAY 0.510638 (3075 3475);
PAINT RED (3075 3475);
FORCEPROP 1 LAST TOLERANCE 10%
J 2
(3075 3525);
DISPLAY 0.510638 (3075 3525);
FORCEPROP 1 LAST VALUE 0.1UF
J 2
(3100 3625);
DISPLAY 0.510638 (3100 3625);
FORCEPROP 2 LAST ROOM ADC1_BOM2
J 0
(3200 3575);
DISPLAY 0.638298 (3200 3575);
FORCEPROP 1 LAST $LOCATION C2177
J 2
(3150 3675);
DISPLAY 0.787234 (3150 3675);
FORCEPROP 1 LASTPIN (2925 3650) $PN 1
J 2
(2915 3630);
DISPLAY 0.787234 (2915 3630);
PAINT MONO (2915 3630);
FORCEPROP 1 LASTPIN (2925 3450) $PN 2
J 2
(2915 3430);
DISPLAY 0.787234 (2915 3430);
PAINT MONO (2915 3430);
FORCEPROP 1 LAST PATH I311
J 2
(2875 3700);
DISPLAY 0.978723 (2875 3700);
PAINT WHITE (2875 3700);
DISPLAY INVISIBLE (2875 3700);
FORCEPROP 2 LAST CDS_LIB pure_quanta
J 0
(2925 3550);
DISPLAY INVISIBLE (2925 3550);
FORCEPROP 0 LAST CDS_LOCATION C2177
J 0
(3025 3700);
DISPLAY 1.021277 (3025 3700);
DISPLAY INVISIBLE (3025 3700);
FORCEPROP 0 LAST $SEC 1
J 0
(3025 3700);
DISPLAY 0.680851 (3025 3700);
PAINT MONO (3025 3700);
DISPLAY INVISIBLE (3025 3700);
FORCEPROP 0 LAST CDS_SEC 1
J 0
(3025 3700);
DISPLAY 1.021277 (3025 3700);
DISPLAY INVISIBLE (3025 3700);
FORCEADD UNIVERSAL_GND..1
(2925 3375);
FORCEPROP 3 LASTPIN (2925 3425) SIG_NAME GND\g
J 0
(2935 3435);
DISPLAY 0.659574 (2935 3435);
PAINT MONO (2935 3435);
DISPLAY INVISIBLE (2935 3435);
FORCEPROP 1 LAST PATH I312
J 0
(3000 3375);
DISPLAY 0.872340 (3000 3375);
PAINT AQUA (3000 3375);
DISPLAY INVISIBLE (3000 3375);
FORCEPROP 2 LAST CDS_LIB logical_power
J 0
(2925 3375);
DISPLAY INVISIBLE (2925 3375);
FORCEPROP 1 LAST HDL_POWER GND
J 1
(2950 3300);
DISPLAY 0.872340 (2950 3300);
PAINT GREEN (2950 3300);
DISPLAY INVISIBLE (2950 3300);
FORCEADD Q_RES..1
(2250 5200);
FORCEPROP 1 LAST PART_NUMBER CS00002JB13
J 0
(2175 5150);
DISPLAY 0.319149 (2175 5150);
DISPLAY INVISIBLE (2175 5150);
FORCEPROP 1 LAST MATERIAL EMPTY
J 0
(2475 5200);
DISPLAY 0.404255 (2475 5200);
PAINT RED (2475 5200);
FORCEPROP 1 LAST VALUE 0
J 2
(2400 5200);
DISPLAY 0.404255 (2400 5200);
FORCEPROP 1 LAST TOLERANCE 5%
J 0
(2425 5200);
DISPLAY 0.404255 (2425 5200);
FORCEPROP 0 LAST ROOM NIC1_P12V_MAM_MAM_BOM1
J 0
(2125 5250);
DISPLAY 0.638298 (2125 5250);
FORCEPROP 1 LAST $LOCATION R3863
J 0
(2075 5200);
DISPLAY 0.510638 (2075 5200);
FORCEPROP 1 LASTPIN (2150 5200) $PN 1
J 0
(2162 5212);
DISPLAY 0.787234 (2162 5212);
PAINT MONO (2162 5212);
FORCEPROP 1 LASTPIN (2350 5200) $PN 2
J 0
(2312 5212);
DISPLAY 0.787234 (2312 5212);
PAINT MONO (2312 5212);
FORCEPROP 1 LAST PATH I313
J 0
(2200 5350);
DISPLAY 0.978723 (2200 5350);
PAINT WHITE (2200 5350);
DISPLAY INVISIBLE (2200 5350);
FORCEPROP 1 LAST PACK_TYPE 0402LF
J 0
(2500 5200);
DISPLAY 0.510638 (2500 5200);
DISPLAY INVISIBLE (2500 5200);
FORCEPROP 1 LAST WATTAGE 1/16W
J 2
(2350 5125);
DISPLAY 0.319149 (2350 5125);
DISPLAY INVISIBLE (2350 5125);
FORCEPROP 2 LAST CDS_LIB pure_quanta
J 0
(2250 5200);
DISPLAY INVISIBLE (2250 5200);
FORCEPROP 0 LAST CDS_LOCATION R3863
J 0
(2125 5250);
DISPLAY 1.021277 (2125 5250);
DISPLAY INVISIBLE (2125 5250);
FORCEPROP 0 LAST $SEC 1
J 0
(2125 5250);
DISPLAY 0.680851 (2125 5250);
PAINT MONO (2125 5250);
DISPLAY INVISIBLE (2125 5250);
FORCEPROP 0 LAST CDS_SEC 1
J 0
(2125 5250);
DISPLAY 1.021277 (2125 5250);
DISPLAY INVISIBLE (2125 5250);
FORCEADD Q_RES..1
(2250 5050);
FORCEPROP 1 LAST PART_NUMBER CS00002JB13
J 0
(2175 5000);
DISPLAY 0.319149 (2175 5000);
DISPLAY INVISIBLE (2175 5000);
FORCEPROP 1 LAST TOLERANCE 5%
J 0
(2425 5050);
DISPLAY 0.404255 (2425 5050);
FORCEPROP 1 LAST VALUE 0
J 2
(2400 5050);
DISPLAY 0.404255 (2400 5050);
FORCEPROP 1 LAST MATERIAL EMPTY
J 0
(2475 5050);
DISPLAY 0.404255 (2475 5050);
PAINT RED (2475 5050);
FORCEPROP 0 LAST ROOM NIC1_P12V_MPS_MAM_BOM3
J 0
(2150 4975);
DISPLAY 0.638298 (2150 4975);
FORCEPROP 1 LAST $LOCATION R3864
J 0
(2075 5050);
DISPLAY 0.510638 (2075 5050);
FORCEPROP 1 LASTPIN (2150 5050) $PN 1
J 0
(2162 5062);
DISPLAY 0.787234 (2162 5062);
PAINT MONO (2162 5062);
FORCEPROP 1 LASTPIN (2350 5050) $PN 2
J 0
(2312 5062);
DISPLAY 0.787234 (2312 5062);
PAINT MONO (2312 5062);
FORCEPROP 1 LAST PATH I314
J 0
(2200 5200);
DISPLAY 0.978723 (2200 5200);
PAINT WHITE (2200 5200);
DISPLAY INVISIBLE (2200 5200);
FORCEPROP 2 LAST CDS_LIB pure_quanta
J 0
(2250 5050);
DISPLAY INVISIBLE (2250 5050);
FORCEPROP 1 LAST WATTAGE 1/16W
J 2
(2350 4975);
DISPLAY 0.319149 (2350 4975);
DISPLAY INVISIBLE (2350 4975);
FORCEPROP 1 LAST PACK_TYPE 0402LF
J 0
(2500 5050);
DISPLAY 0.510638 (2500 5050);
DISPLAY INVISIBLE (2500 5050);
FORCEPROP 0 LAST CDS_LOCATION R3864
J 0
(2125 5100);
DISPLAY 1.021277 (2125 5100);
DISPLAY INVISIBLE (2125 5100);
FORCEPROP 0 LAST $SEC 1
J 0
(2125 5100);
DISPLAY 0.680851 (2125 5100);
PAINT MONO (2125 5100);
DISPLAY INVISIBLE (2125 5100);
FORCEPROP 0 LAST CDS_SEC 1
J 0
(2125 5100);
DISPLAY 1.021277 (2125 5100);
DISPLAY INVISIBLE (2125 5100);
FORCEADD Q_RES..1
(2250 4700);
FORCEPROP 1 LAST PART_NUMBER CS00002JB13
J 0
(2175 4650);
DISPLAY 0.319149 (2175 4650);
DISPLAY INVISIBLE (2175 4650);
FORCEPROP 1 LAST TOLERANCE 5%
J 0
(2425 4700);
DISPLAY 0.404255 (2425 4700);
FORCEPROP 1 LAST VALUE 0
J 2
(2400 4700);
DISPLAY 0.404255 (2400 4700);
FORCEPROP 1 LAST MATERIAL EMPTY
J 0
(2475 4700);
DISPLAY 0.404255 (2475 4700);
FORCEPROP 0 LAST ROOM1 NIC1_P12V_MAM_TIC_BOM2
J 0
(2150 4775);
DISPLAY 0.404255 (2150 4775);
FORCEPROP 1 LAST $LOCATION R3865
J 0
(2075 4700);
DISPLAY 0.510638 (2075 4700);
FORCEPROP 1 LASTPIN (2150 4700) $PN 1
J 0
(2162 4712);
DISPLAY 0.787234 (2162 4712);
PAINT MONO (2162 4712);
FORCEPROP 1 LASTPIN (2350 4700) $PN 2
J 0
(2312 4712);
DISPLAY 0.787234 (2312 4712);
PAINT MONO (2312 4712);
FORCEPROP 1 LAST PACK_TYPE 0402LF
J 0
(2500 4700);
DISPLAY 0.510638 (2500 4700);
DISPLAY INVISIBLE (2500 4700);
FORCEPROP 1 LAST WATTAGE 1/16W
J 2
(2350 4625);
DISPLAY 0.319149 (2350 4625);
DISPLAY INVISIBLE (2350 4625);
FORCEPROP 2 LAST CDS_LIB pure_quanta
J 0
(2250 4700);
DISPLAY INVISIBLE (2250 4700);
FORCEPROP 1 LAST PATH I315
J 0
(2200 4850);
DISPLAY 0.978723 (2200 4850);
PAINT WHITE (2200 4850);
DISPLAY INVISIBLE (2200 4850);
FORCEPROP 0 LAST CDS_LOCATION R3865
J 0
(2125 4750);
DISPLAY 1.021277 (2125 4750);
DISPLAY INVISIBLE (2125 4750);
FORCEPROP 0 LAST $SEC 1
J 0
(2125 4750);
DISPLAY 0.680851 (2125 4750);
PAINT MONO (2125 4750);
DISPLAY INVISIBLE (2125 4750);
FORCEPROP 0 LAST CDS_SEC 1
J 0
(2125 4750);
DISPLAY 1.021277 (2125 4750);
DISPLAY INVISIBLE (2125 4750);
FORCEADD Q_RES..1
(2250 4550);
FORCEPROP 1 LAST PART_NUMBER CS00002JB13
J 0
(2175 4500);
DISPLAY 0.319149 (2175 4500);
DISPLAY INVISIBLE (2175 4500);
FORCEPROP 1 LAST VALUE 0
J 2
(2400 4550);
DISPLAY 0.404255 (2400 4550);
FORCEPROP 1 LAST TOLERANCE 5%
J 0
(2425 4550);
DISPLAY 0.404255 (2425 4550);
FORCEPROP 1 LAST MATERIAL CHIP
J 0
(2475 4550);
DISPLAY 0.404255 (2475 4550);
PAINT RED (2475 4550);
FORCEPROP 0 LAST ROOM1 NIC1_P12V_MPS_TIC_BOM4
J 0
(2100 4500);
DISPLAY 0.510638 (2100 4500);
FORCEPROP 1 LAST $LOCATION R3866
J 0
(2075 4550);
DISPLAY 0.510638 (2075 4550);
FORCEPROP 1 LASTPIN (2150 4550) $PN 1
J 0
(2162 4562);
DISPLAY 0.787234 (2162 4562);
PAINT MONO (2162 4562);
FORCEPROP 1 LASTPIN (2350 4550) $PN 2
J 0
(2312 4562);
DISPLAY 0.787234 (2312 4562);
PAINT MONO (2312 4562);
FORCEPROP 1 LAST PACK_TYPE 0402LF
J 0
(2500 4550);
DISPLAY 0.510638 (2500 4550);
DISPLAY INVISIBLE (2500 4550);
FORCEPROP 1 LAST WATTAGE 1/16W
J 2
(2350 4475);
DISPLAY 0.319149 (2350 4475);
DISPLAY INVISIBLE (2350 4475);
FORCEPROP 2 LAST CDS_LIB pure_quanta
J 0
(2250 4550);
DISPLAY INVISIBLE (2250 4550);
FORCEPROP 1 LAST PATH I316
J 0
(2200 4700);
DISPLAY 0.978723 (2200 4700);
PAINT WHITE (2200 4700);
DISPLAY INVISIBLE (2200 4700);
FORCEPROP 0 LAST CDS_LOCATION R3866
J 0
(2125 4600);
DISPLAY 1.021277 (2125 4600);
DISPLAY INVISIBLE (2125 4600);
FORCEPROP 0 LAST $SEC 1
J 0
(2125 4600);
DISPLAY 0.680851 (2125 4600);
PAINT MONO (2125 4600);
DISPLAY INVISIBLE (2125 4600);
FORCEPROP 0 LAST CDS_SEC 1
J 0
(2125 4600);
DISPLAY 1.021277 (2125 4600);
DISPLAY INVISIBLE (2125 4600);
FORCEADD OFFPAGE..1
(1325 5200);
FORCEPROP 2 LAST $XR0 156 
J 0
(1073 5200);
DISPLAY 0.638298 (1073 5200);
PAINT MONO (1073 5200);
FORCEPROP 2 LAST PATH I317
J 0
(900 5250);
DISPLAY 1.021277 (900 5250);
DISPLAY INVISIBLE (900 5250);
FORCEPROP 1 LAST COMMENT_BODY TRUE
J 0
(1450 5100);
DISPLAY 0.872340 (1450 5100);
PAINT GREEN (1450 5100);
DISPLAY INVISIBLE (1450 5100);
FORCEPROP 1 LAST OFFPAGE TRUE
J 0
(1650 5075);
DISPLAY 0.872340 (1650 5075);
PAINT GREEN (1650 5075);
DISPLAY INVISIBLE (1650 5075);
FORCEPROP 2 LAST CDS_LIB standard
J 0
(1325 5200);
DISPLAY INVISIBLE (1325 5200);
FORCEADD OFFPAGE..1
(1325 5050);
FORCEPROP 2 LAST $XR0 157 
J 0
(1073 5050);
DISPLAY 0.638298 (1073 5050);
PAINT MONO (1073 5050);
FORCEPROP 2 LAST PATH I318
J 0
(900 5100);
DISPLAY 1.021277 (900 5100);
DISPLAY INVISIBLE (900 5100);
FORCEPROP 2 LAST CDS_LIB standard
J 0
(1325 5050);
DISPLAY INVISIBLE (1325 5050);
FORCEPROP 1 LAST OFFPAGE TRUE
J 0
(1650 4925);
DISPLAY 0.872340 (1650 4925);
PAINT GREEN (1650 4925);
DISPLAY INVISIBLE (1650 4925);
FORCEPROP 1 LAST COMMENT_BODY TRUE
J 0
(1450 4950);
DISPLAY 0.872340 (1450 4950);
PAINT GREEN (1450 4950);
DISPLAY INVISIBLE (1450 4950);
FORCEADD OFFPAGE..1
(1325 4550);
FORCEPROP 2 LAST $XR0 157 
J 0
(1073 4550);
DISPLAY 0.638298 (1073 4550);
PAINT MONO (1073 4550);
FORCEPROP 2 LAST PATH I319
J 0
(900 4600);
DISPLAY 1.021277 (900 4600);
DISPLAY INVISIBLE (900 4600);
FORCEPROP 1 LAST COMMENT_BODY TRUE
J 0
(1450 4450);
DISPLAY 0.872340 (1450 4450);
PAINT GREEN (1450 4450);
DISPLAY INVISIBLE (1450 4450);
FORCEPROP 1 LAST OFFPAGE TRUE
J 0
(1650 4425);
DISPLAY 0.872340 (1650 4425);
PAINT GREEN (1650 4425);
DISPLAY INVISIBLE (1650 4425);
FORCEPROP 2 LAST CDS_LIB standard
J 0
(1325 4550);
DISPLAY INVISIBLE (1325 4550);
FORCEADD OFFPAGE..1
(1325 4700);
FORCEPROP 2 LAST $XR0 156 
J 0
(1073 4700);
DISPLAY 0.638298 (1073 4700);
PAINT MONO (1073 4700);
FORCEPROP 2 LAST PATH I320
J 0
(900 4750);
DISPLAY 1.021277 (900 4750);
DISPLAY INVISIBLE (900 4750);
FORCEPROP 2 LAST CDS_LIB standard
J 0
(1325 4700);
DISPLAY INVISIBLE (1325 4700);
FORCEPROP 1 LAST OFFPAGE TRUE
J 0
(1650 4575);
DISPLAY 0.872340 (1650 4575);
PAINT GREEN (1650 4575);
DISPLAY INVISIBLE (1650 4575);
FORCEPROP 1 LAST COMMENT_BODY TRUE
J 0
(1450 4600);
DISPLAY 0.872340 (1450 4600);
PAINT GREEN (1450 4600);
DISPLAY INVISIBLE (1450 4600);
FORCEADD Q_RES..1
(2225 4225);
FORCEPROP 1 LAST PART_NUMBER CS00002JB13
J 0
(2150 4175);
DISPLAY 0.319149 (2150 4175);
DISPLAY INVISIBLE (2150 4175);
FORCEPROP 1 LAST VALUE 0
J 2
(2375 4225);
DISPLAY 0.404255 (2375 4225);
FORCEPROP 1 LAST MATERIAL EMPTY
J 0
(2450 4225);
DISPLAY 0.404255 (2450 4225);
PAINT RED (2450 4225);
FORCEPROP 1 LAST TOLERANCE 5%
J 0
(2400 4225);
DISPLAY 0.404255 (2400 4225);
FORCEPROP 2 LAST ROOM NIC1_P12V_MAM_MAM_BOM1 
J 0
(2450 4300);
DISPLAY 0.510638 (2450 4300);
FORCEPROP 1 LAST $LOCATION R3859
J 0
(2050 4225);
DISPLAY 0.510638 (2050 4225);
FORCEPROP 1 LASTPIN (2125 4225) $PN 1
J 0
(2137 4237);
DISPLAY 0.787234 (2137 4237);
PAINT MONO (2137 4237);
FORCEPROP 1 LASTPIN (2325 4225) $PN 2
J 0
(2287 4237);
DISPLAY 0.787234 (2287 4237);
PAINT MONO (2287 4237);
FORCEPROP 2 LAST CDS_LIB pure_quanta
J 0
(2225 4225);
DISPLAY INVISIBLE (2225 4225);
FORCEPROP 1 LAST WATTAGE 1/16W
J 2
(2325 4150);
DISPLAY 0.319149 (2325 4150);
DISPLAY INVISIBLE (2325 4150);
FORCEPROP 1 LAST PACK_TYPE 0402LF
J 0
(2475 4225);
DISPLAY 0.510638 (2475 4225);
DISPLAY INVISIBLE (2475 4225);
FORCEPROP 1 LAST PATH I321
J 0
(2175 4375);
DISPLAY 0.978723 (2175 4375);
PAINT WHITE (2175 4375);
DISPLAY INVISIBLE (2175 4375);
FORCEPROP 0 LAST CDS_LOCATION R3859
J 0
(2100 4275);
DISPLAY 1.021277 (2100 4275);
DISPLAY INVISIBLE (2100 4275);
FORCEPROP 0 LAST $SEC 1
J 0
(2100 4275);
DISPLAY 0.680851 (2100 4275);
PAINT MONO (2100 4275);
DISPLAY INVISIBLE (2100 4275);
FORCEPROP 0 LAST CDS_SEC 1
J 0
(2100 4275);
DISPLAY 1.021277 (2100 4275);
DISPLAY INVISIBLE (2100 4275);
FORCEADD Q_RES..1
(2225 4075);
FORCEPROP 1 LAST PART_NUMBER CS00002JB13
J 0
(2150 4025);
DISPLAY 0.319149 (2150 4025);
DISPLAY INVISIBLE (2150 4025);
FORCEPROP 1 LAST VALUE 0
J 2
(2375 4075);
DISPLAY 0.404255 (2375 4075);
FORCEPROP 1 LAST TOLERANCE 5%
J 0
(2400 4075);
DISPLAY 0.404255 (2400 4075);
FORCEPROP 2 LAST ROOM NIC1_P12V_MPS_MAM_BOM3 
J 0
(2450 4150);
DISPLAY 0.510638 (2450 4150);
FORCEPROP 1 LAST MATERIAL EMPTY
J 0
(2450 4075);
DISPLAY 0.404255 (2450 4075);
PAINT RED (2450 4075);
FORCEPROP 1 LAST $LOCATION R3860
J 0
(2050 4075);
DISPLAY 0.510638 (2050 4075);
FORCEPROP 1 LASTPIN (2125 4075) $PN 1
J 0
(2137 4087);
DISPLAY 0.787234 (2137 4087);
PAINT MONO (2137 4087);
FORCEPROP 1 LASTPIN (2325 4075) $PN 2
J 0
(2287 4087);
DISPLAY 0.787234 (2287 4087);
PAINT MONO (2287 4087);
FORCEPROP 1 LAST PACK_TYPE 0402LF
J 0
(2475 4075);
DISPLAY 0.510638 (2475 4075);
DISPLAY INVISIBLE (2475 4075);
FORCEPROP 1 LAST WATTAGE 1/16W
J 2
(2325 4000);
DISPLAY 0.319149 (2325 4000);
DISPLAY INVISIBLE (2325 4000);
FORCEPROP 2 LAST CDS_LIB pure_quanta
J 0
(2225 4075);
DISPLAY INVISIBLE (2225 4075);
FORCEPROP 1 LAST PATH I322
J 0
(2175 4225);
DISPLAY 0.978723 (2175 4225);
PAINT WHITE (2175 4225);
DISPLAY INVISIBLE (2175 4225);
FORCEPROP 0 LAST CDS_LOCATION R3860
J 0
(2100 4125);
DISPLAY 1.021277 (2100 4125);
DISPLAY INVISIBLE (2100 4125);
FORCEPROP 0 LAST $SEC 1
J 0
(2100 4125);
DISPLAY 0.680851 (2100 4125);
PAINT MONO (2100 4125);
DISPLAY INVISIBLE (2100 4125);
FORCEPROP 0 LAST CDS_SEC 1
J 0
(2100 4125);
DISPLAY 1.021277 (2100 4125);
DISPLAY INVISIBLE (2100 4125);
FORCEADD Q_RES..1
(2225 3725);
FORCEPROP 1 LAST PART_NUMBER CS00002JB13
J 0
(2150 3675);
DISPLAY 0.319149 (2150 3675);
DISPLAY INVISIBLE (2150 3675);
FORCEPROP 1 LAST VALUE 0
J 2
(2375 3725);
DISPLAY 0.404255 (2375 3725);
FORCEPROP 1 LAST MATERIAL EMPTY
J 0
(2450 3725);
DISPLAY 0.404255 (2450 3725);
FORCEPROP 1 LAST TOLERANCE 5%
J 0
(2400 3725);
DISPLAY 0.404255 (2400 3725);
FORCEPROP 2 LAST ROOM1 NIC1_P12V_MAM_TIC_BOM2 
J 0
(2100 3800);
DISPLAY 0.510638 (2100 3800);
FORCEPROP 1 LAST $LOCATION R3861
J 0
(2050 3725);
DISPLAY 0.510638 (2050 3725);
FORCEPROP 1 LASTPIN (2125 3725) $PN 1
J 0
(2137 3737);
DISPLAY 0.787234 (2137 3737);
PAINT MONO (2137 3737);
FORCEPROP 1 LASTPIN (2325 3725) $PN 2
J 0
(2287 3737);
DISPLAY 0.787234 (2287 3737);
PAINT MONO (2287 3737);
FORCEPROP 1 LAST PATH I323
J 0
(2175 3875);
DISPLAY 0.978723 (2175 3875);
PAINT WHITE (2175 3875);
DISPLAY INVISIBLE (2175 3875);
FORCEPROP 2 LAST CDS_LIB pure_quanta
J 0
(2225 3725);
DISPLAY INVISIBLE (2225 3725);
FORCEPROP 1 LAST WATTAGE 1/16W
J 2
(2325 3650);
DISPLAY 0.319149 (2325 3650);
DISPLAY INVISIBLE (2325 3650);
FORCEPROP 1 LAST PACK_TYPE 0402LF
J 0
(2475 3725);
DISPLAY 0.510638 (2475 3725);
DISPLAY INVISIBLE (2475 3725);
FORCEPROP 0 LAST CDS_LOCATION R3861
J 0
(2100 3775);
DISPLAY 1.021277 (2100 3775);
DISPLAY INVISIBLE (2100 3775);
FORCEPROP 0 LAST $SEC 1
J 0
(2100 3775);
DISPLAY 0.680851 (2100 3775);
PAINT MONO (2100 3775);
DISPLAY INVISIBLE (2100 3775);
FORCEPROP 0 LAST CDS_SEC 1
J 0
(2100 3775);
DISPLAY 1.021277 (2100 3775);
DISPLAY INVISIBLE (2100 3775);
FORCEADD Q_RES..1
(2225 3575);
FORCEPROP 1 LAST PART_NUMBER CS00002JB13
J 0
(2150 3525);
DISPLAY 0.319149 (2150 3525);
DISPLAY INVISIBLE (2150 3525);
FORCEPROP 1 LAST TOLERANCE 5%
J 0
(2400 3575);
DISPLAY 0.404255 (2400 3575);
FORCEPROP 1 LAST MATERIAL CHIP
J 0
(2450 3575);
DISPLAY 0.404255 (2450 3575);
PAINT RED (2450 3575);
FORCEPROP 1 LAST VALUE 0
J 2
(2375 3575);
DISPLAY 0.404255 (2375 3575);
FORCEPROP 2 LAST ROOM1 NIC1_P12V_MPS_TIC_BOM4 
J 0
(2100 3650);
DISPLAY 0.510638 (2100 3650);
FORCEPROP 1 LAST $LOCATION R3862
J 0
(2050 3575);
DISPLAY 0.510638 (2050 3575);
FORCEPROP 1 LASTPIN (2125 3575) $PN 1
J 0
(2137 3587);
DISPLAY 0.787234 (2137 3587);
PAINT MONO (2137 3587);
FORCEPROP 1 LASTPIN (2325 3575) $PN 2
J 0
(2287 3587);
DISPLAY 0.787234 (2287 3587);
PAINT MONO (2287 3587);
FORCEPROP 1 LAST PATH I324
J 0
(2175 3725);
DISPLAY 0.978723 (2175 3725);
PAINT WHITE (2175 3725);
DISPLAY INVISIBLE (2175 3725);
FORCEPROP 2 LAST CDS_LIB pure_quanta
J 0
(2225 3575);
DISPLAY INVISIBLE (2225 3575);
FORCEPROP 1 LAST WATTAGE 1/16W
J 2
(2325 3500);
DISPLAY 0.319149 (2325 3500);
DISPLAY INVISIBLE (2325 3500);
FORCEPROP 1 LAST PACK_TYPE 0402LF
J 0
(2475 3575);
DISPLAY 0.510638 (2475 3575);
DISPLAY INVISIBLE (2475 3575);
FORCEPROP 0 LAST CDS_LOCATION R3862
J 0
(2100 3625);
DISPLAY 1.021277 (2100 3625);
DISPLAY INVISIBLE (2100 3625);
FORCEPROP 0 LAST $SEC 1
J 0
(2100 3625);
DISPLAY 0.680851 (2100 3625);
PAINT MONO (2100 3625);
DISPLAY INVISIBLE (2100 3625);
FORCEPROP 0 LAST CDS_SEC 1
J 0
(2100 3625);
DISPLAY 1.021277 (2100 3625);
DISPLAY INVISIBLE (2100 3625);
FORCEADD OFFPAGE..1
(1300 4075);
FORCEPROP 2 LAST $XR0 163 
J 0
(1048 4075);
DISPLAY 0.638298 (1048 4075);
PAINT MONO (1048 4075);
FORCEPROP 2 LAST PATH I325
J 0
(875 4125);
DISPLAY 1.021277 (875 4125);
DISPLAY INVISIBLE (875 4125);
FORCEPROP 1 LAST COMMENT_BODY TRUE
J 0
(1425 3975);
DISPLAY 0.872340 (1425 3975);
PAINT GREEN (1425 3975);
DISPLAY INVISIBLE (1425 3975);
FORCEPROP 1 LAST OFFPAGE TRUE
J 0
(1625 3950);
DISPLAY 0.872340 (1625 3950);
PAINT GREEN (1625 3950);
DISPLAY INVISIBLE (1625 3950);
FORCEPROP 2 LAST CDS_LIB standard
J 0
(1300 4075);
DISPLAY INVISIBLE (1300 4075);
FORCEADD OFFPAGE..1
(1300 4225);
FORCEPROP 2 LAST $XR0 162 
J 0
(1048 4225);
DISPLAY 0.638298 (1048 4225);
PAINT MONO (1048 4225);
FORCEPROP 2 LAST PATH I326
J 0
(875 4275);
DISPLAY 1.021277 (875 4275);
DISPLAY INVISIBLE (875 4275);
FORCEPROP 2 LAST CDS_LIB standard
J 0
(1300 4225);
DISPLAY INVISIBLE (1300 4225);
FORCEPROP 1 LAST OFFPAGE TRUE
J 0
(1625 4100);
DISPLAY 0.872340 (1625 4100);
PAINT GREEN (1625 4100);
DISPLAY INVISIBLE (1625 4100);
FORCEPROP 1 LAST COMMENT_BODY TRUE
J 0
(1425 4125);
DISPLAY 0.872340 (1425 4125);
PAINT GREEN (1425 4125);
DISPLAY INVISIBLE (1425 4125);
FORCEADD OFFPAGE..1
(1300 3725);
FORCEPROP 2 LAST $XR0 162 
J 0
(1048 3725);
DISPLAY 0.638298 (1048 3725);
PAINT MONO (1048 3725);
FORCEPROP 2 LAST PATH I327
J 0
(875 3775);
DISPLAY 1.021277 (875 3775);
DISPLAY INVISIBLE (875 3775);
FORCEPROP 1 LAST COMMENT_BODY TRUE
J 0
(1425 3625);
DISPLAY 0.872340 (1425 3625);
PAINT GREEN (1425 3625);
DISPLAY INVISIBLE (1425 3625);
FORCEPROP 1 LAST OFFPAGE TRUE
J 0
(1625 3600);
DISPLAY 0.872340 (1625 3600);
PAINT GREEN (1625 3600);
DISPLAY INVISIBLE (1625 3600);
FORCEPROP 2 LAST CDS_LIB standard
J 0
(1300 3725);
DISPLAY INVISIBLE (1300 3725);
FORCEADD OFFPAGE..1
(1300 3575);
FORCEPROP 2 LAST $XR0 163 
J 0
(1048 3575);
DISPLAY 0.638298 (1048 3575);
PAINT MONO (1048 3575);
FORCEPROP 2 LAST PATH I328
J 0
(875 3625);
DISPLAY 1.021277 (875 3625);
DISPLAY INVISIBLE (875 3625);
FORCEPROP 2 LAST CDS_LIB standard
J 0
(1300 3575);
DISPLAY INVISIBLE (1300 3575);
FORCEPROP 1 LAST OFFPAGE TRUE
J 0
(1625 3450);
DISPLAY 0.872340 (1625 3450);
PAINT GREEN (1625 3450);
DISPLAY INVISIBLE (1625 3450);
FORCEPROP 1 LAST COMMENT_BODY TRUE
J 0
(1425 3475);
DISPLAY 0.872340 (1425 3475);
PAINT GREEN (1425 3475);
DISPLAY INVISIBLE (1425 3475);
FORCEADD OFFPAGE..2
(3175 3225);
FORCEPROP 2 LAST $XR0 250 
J 0
(3364 3225);
DISPLAY 0.638298 (3364 3225);
PAINT MONO (3364 3225);
FORCEPROP 2 LAST CDS_LIB standard
J 0
(3175 3225);
DISPLAY INVISIBLE (3175 3225);
FORCEPROP 1 LAST COMMENT_BODY TRUE
J 0
(3130 3130);
DISPLAY 0.872340 (3130 3130);
PAINT GREEN (3130 3130);
DISPLAY INVISIBLE (3130 3130);
FORCEPROP 1 LAST OFFPAGE TRUE
J 0
(3500 3100);
DISPLAY 0.872340 (3500 3100);
DISPLAY INVISIBLE (3500 3100);
FORCEPROP 2 LAST PATH I329
J 0
(3375 3275);
DISPLAY 1.021277 (3375 3275);
DISPLAY INVISIBLE (3375 3275);
FORCEADD Q_RES..1
(2200 3225);
FORCEPROP 1 LAST PART_NUMBER CS00002JB13
J 0
(2125 3175);
DISPLAY 0.319149 (2125 3175);
DISPLAY INVISIBLE (2125 3175);
FORCEPROP 1 LAST VALUE 0
J 2
(2350 3225);
DISPLAY 0.404255 (2350 3225);
FORCEPROP 1 LAST TOLERANCE 5%
J 0
(2375 3225);
DISPLAY 0.404255 (2375 3225);
FORCEPROP 1 LAST MATERIAL EMPTY
J 0
(2425 3225);
DISPLAY 0.404255 (2425 3225);
PAINT RED (2425 3225);
FORCEPROP 0 LAST ROOM E1S1_P12V_MAM_MAM_BOM1
J 0
(2025 3300);
DISPLAY 0.510638 (2025 3300);
FORCEPROP 1 LAST $LOCATION R3939
J 0
(2025 3225);
DISPLAY 0.510638 (2025 3225);
FORCEPROP 1 LASTPIN (2100 3225) $PN 1
J 0
(2112 3237);
DISPLAY 0.787234 (2112 3237);
PAINT MONO (2112 3237);
FORCEPROP 1 LASTPIN (2300 3225) $PN 2
J 0
(2262 3237);
DISPLAY 0.787234 (2262 3237);
PAINT MONO (2262 3237);
FORCEPROP 2 LAST CDS_LIB pure_quanta
J 0
(2200 3225);
DISPLAY INVISIBLE (2200 3225);
FORCEPROP 1 LAST WATTAGE 1/16W
J 2
(2300 3150);
DISPLAY 0.319149 (2300 3150);
DISPLAY INVISIBLE (2300 3150);
FORCEPROP 1 LAST PACK_TYPE 0402LF
J 0
(2450 3225);
DISPLAY 0.510638 (2450 3225);
DISPLAY INVISIBLE (2450 3225);
FORCEPROP 1 LAST PATH I330
J 0
(2150 3375);
DISPLAY 0.978723 (2150 3375);
PAINT WHITE (2150 3375);
DISPLAY INVISIBLE (2150 3375);
FORCEPROP 0 LAST CDS_LOCATION R3939
J 0
(2075 3275);
DISPLAY 1.021277 (2075 3275);
DISPLAY INVISIBLE (2075 3275);
FORCEPROP 0 LAST $SEC 1
J 0
(2075 3275);
DISPLAY 0.680851 (2075 3275);
PAINT MONO (2075 3275);
DISPLAY INVISIBLE (2075 3275);
FORCEPROP 0 LAST CDS_SEC 1
J 0
(2075 3275);
DISPLAY 1.021277 (2075 3275);
DISPLAY INVISIBLE (2075 3275);
FORCEADD OFFPAGE..1
(1275 3225);
FORCEPROP 2 LAST $XR0 192 
J 0
(1023 3225);
DISPLAY 0.638298 (1023 3225);
PAINT MONO (1023 3225);
FORCEPROP 1 LAST COMMENT_BODY TRUE
J 0
(1400 3125);
DISPLAY 0.872340 (1400 3125);
PAINT GREEN (1400 3125);
DISPLAY INVISIBLE (1400 3125);
FORCEPROP 1 LAST OFFPAGE TRUE
J 0
(1600 3100);
DISPLAY 0.872340 (1600 3100);
PAINT GREEN (1600 3100);
DISPLAY INVISIBLE (1600 3100);
FORCEPROP 2 LAST CDS_LIB standard
J 0
(1275 3225);
DISPLAY INVISIBLE (1275 3225);
FORCEPROP 2 LAST PATH I331
J 0
(850 3275);
DISPLAY 1.021277 (850 3275);
DISPLAY INVISIBLE (850 3275);
FORCEADD OFFPAGE..2
(3175 2725);
FORCEPROP 2 LAST $XR0 250 
J 0
(3364 2725);
DISPLAY 0.638298 (3364 2725);
PAINT MONO (3364 2725);
FORCEPROP 2 LAST PATH I332
J 0
(3375 2775);
DISPLAY 1.021277 (3375 2775);
DISPLAY INVISIBLE (3375 2775);
FORCEPROP 2 LAST CDS_LIB standard
J 0
(3175 2725);
DISPLAY INVISIBLE (3175 2725);
FORCEPROP 1 LAST COMMENT_BODY TRUE
J 0
(3130 2630);
DISPLAY 0.872340 (3130 2630);
PAINT GREEN (3130 2630);
DISPLAY INVISIBLE (3130 2630);
FORCEPROP 1 LAST OFFPAGE TRUE
J 0
(3500 2600);
DISPLAY 0.872340 (3500 2600);
DISPLAY INVISIBLE (3500 2600);
FORCEADD Q_CAP..1
(2925 3075);
FORCEPROP 1 LAST PART_NUMBER CH11006JB18
J 0
(2975 2925);
DISPLAY 0.510638 (2975 2925);
DISPLAY INVISIBLE (2975 2925);
FORCEPROP 1 LAST PACK_TYPE 0402
J 0
(2975 2875);
DISPLAY 0.510638 (2975 2875);
FORCEPROP 1 LAST TOLERANCE 5%
J 0
(2975 3025);
DISPLAY 0.510638 (2975 3025);
FORCEPROP 1 LAST VOLTAGE 50V
J 0
(2975 3075);
DISPLAY 0.510638 (2975 3075);
FORCEPROP 1 LAST MATERIAL EMPTY
J 0
(2975 2975);
DISPLAY 0.510638 (2975 2975);
FORCEPROP 2 LAST ROOM ADC1_BOM1
J 0
(3050 3050);
DISPLAY 0.638298 (3050 3050);
FORCEPROP 1 LAST VALUE 100PF
J 0
(2975 3125);
DISPLAY 0.510638 (2975 3125);
FORCEPROP 1 LAST $LOCATION C2195
J 0
(2975 3175);
DISPLAY 0.510638 (2975 3175);
FORCEPROP 1 LASTPIN (2925 3175) $PN 1
J 0
(2935 3155);
DISPLAY 0.787234 (2935 3155);
PAINT MONO (2935 3155);
FORCEPROP 1 LASTPIN (2925 2975) $PN 2
J 0
(2935 2955);
DISPLAY 0.787234 (2935 2955);
PAINT MONO (2935 2955);
FORCEPROP 2 LAST CDS_LIB pure_quanta
J 0
(2925 3075);
DISPLAY INVISIBLE (2925 3075);
FORCEPROP 1 LAST PATH I333
J 0
(2975 3225);
DISPLAY 0.978723 (2975 3225);
PAINT WHITE (2975 3225);
DISPLAY INVISIBLE (2975 3225);
FORCEPROP 0 LAST CDS_LOCATION C2195
J 0
(2975 3250);
DISPLAY 1.021277 (2975 3250);
DISPLAY INVISIBLE (2975 3250);
FORCEPROP 2 LAST $SEC 1
J 0
(2975 3275);
DISPLAY 0.680851 (2975 3275);
PAINT MONO (2975 3275);
DISPLAY INVISIBLE (2975 3275);
FORCEPROP 0 LAST CDS_SEC 1
J 0
(2975 3250);
DISPLAY 1.021277 (2975 3250);
DISPLAY INVISIBLE (2975 3250);
FORCEADD UNIVERSAL_GND..1
(2925 2875);
FORCEPROP 3 LASTPIN (2925 2925) SIG_NAME GND\g
J 0
(2935 2935);
DISPLAY 0.659574 (2935 2935);
PAINT MONO (2935 2935);
DISPLAY INVISIBLE (2935 2935);
FORCEPROP 2 LAST CDS_LIB logical_power
J 0
(2925 2875);
DISPLAY INVISIBLE (2925 2875);
FORCEPROP 1 LAST HDL_POWER GND
J 1
(2950 2800);
DISPLAY 0.872340 (2950 2800);
PAINT GREEN (2950 2800);
DISPLAY INVISIBLE (2950 2800);
FORCEPROP 1 LAST PATH I334
J 0
(3000 2875);
DISPLAY 0.872340 (3000 2875);
PAINT AQUA (3000 2875);
DISPLAY INVISIBLE (3000 2875);
FORCEADD UNIVERSAL_GND..1
(2900 2375);
FORCEPROP 3 LASTPIN (2900 2425) SIG_NAME GND\g
J 0
(2910 2435);
DISPLAY 0.659574 (2910 2435);
PAINT MONO (2910 2435);
DISPLAY INVISIBLE (2910 2435);
FORCEPROP 1 LAST PATH I335
J 0
(2975 2375);
DISPLAY 0.872340 (2975 2375);
PAINT AQUA (2975 2375);
DISPLAY INVISIBLE (2975 2375);
FORCEPROP 2 LAST CDS_LIB logical_power
J 0
(2900 2375);
DISPLAY INVISIBLE (2900 2375);
FORCEPROP 1 LAST HDL_POWER GND
J 1
(2925 2300);
DISPLAY 0.872340 (2925 2300);
PAINT GREEN (2925 2300);
DISPLAY INVISIBLE (2925 2300);
FORCEADD Q_CAP..1
R 2
(2900 2550);
FORCEPROP 1 LAST PART_NUMBER CH4104K1B00
J 2
(3200 2425);
DISPLAY 0.510638 (3200 2425);
DISPLAY INVISIBLE (3200 2425);
FORCEPROP 1 LAST VALUE 0.1UF
J 2
(3075 2625);
DISPLAY 0.510638 (3075 2625);
FORCEPROP 2 LAST ROOM ADC1_BOM2
J 0
(3100 2550);
DISPLAY 0.638298 (3100 2550);
FORCEPROP 1 LAST TOLERANCE 10%
J 2
(3050 2525);
DISPLAY 0.510638 (3050 2525);
FORCEPROP 1 LAST MATERIAL X7R
J 2
(3050 2475);
DISPLAY 0.510638 (3050 2475);
PAINT RED (3050 2475);
FORCEPROP 1 LAST VOLTAGE 25V
J 2
(3050 2575);
DISPLAY 0.510638 (3050 2575);
FORCEPROP 1 LAST PACK_TYPE 0402
J 2
(3075 2375);
DISPLAY 0.510638 (3075 2375);
FORCEPROP 1 LAST $LOCATION C2194
J 2
(3125 2675);
DISPLAY 0.787234 (3125 2675);
FORCEPROP 1 LASTPIN (2900 2650) $PN 1
J 2
(2890 2630);
DISPLAY 0.787234 (2890 2630);
PAINT MONO (2890 2630);
FORCEPROP 1 LASTPIN (2900 2450) $PN 2
J 2
(2890 2430);
DISPLAY 0.787234 (2890 2430);
PAINT MONO (2890 2430);
FORCEPROP 1 LAST PATH I336
J 2
(2850 2700);
DISPLAY 0.978723 (2850 2700);
PAINT WHITE (2850 2700);
DISPLAY INVISIBLE (2850 2700);
FORCEPROP 2 LAST CDS_LIB pure_quanta
J 0
(2900 2550);
DISPLAY INVISIBLE (2900 2550);
FORCEPROP 0 LAST CDS_LOCATION C2194
J 0
(3000 2700);
DISPLAY 1.021277 (3000 2700);
DISPLAY INVISIBLE (3000 2700);
FORCEPROP 0 LAST $SEC 1
J 0
(3000 2700);
DISPLAY 0.680851 (3000 2700);
PAINT MONO (3000 2700);
DISPLAY INVISIBLE (3000 2700);
FORCEPROP 0 LAST CDS_SEC 1
J 0
(3000 2700);
DISPLAY 1.021277 (3000 2700);
DISPLAY INVISIBLE (3000 2700);
FORCEADD Q_RES..1
(2200 3075);
FORCEPROP 1 LAST PART_NUMBER CS00002JB13
J 0
(2125 3025);
DISPLAY 0.319149 (2125 3025);
DISPLAY INVISIBLE (2125 3025);
FORCEPROP 1 LAST VALUE 0
J 2
(2350 3075);
DISPLAY 0.404255 (2350 3075);
FORCEPROP 1 LAST TOLERANCE 5%
J 0
(2375 3075);
DISPLAY 0.404255 (2375 3075);
FORCEPROP 1 LAST MATERIAL EMPTY
J 0
(2425 3075);
DISPLAY 0.404255 (2425 3075);
PAINT RED (2425 3075);
FORCEPROP 0 LAST ROOM E1S1_P12V_MPS_MAM_BOM3
J 0
(2000 3025);
DISPLAY 0.510638 (2000 3025);
FORCEPROP 1 LAST $LOCATION R3940
J 0
(2025 3075);
DISPLAY 0.510638 (2025 3075);
FORCEPROP 1 LASTPIN (2100 3075) $PN 1
J 0
(2112 3087);
DISPLAY 0.787234 (2112 3087);
PAINT MONO (2112 3087);
FORCEPROP 1 LASTPIN (2300 3075) $PN 2
J 0
(2262 3087);
DISPLAY 0.787234 (2262 3087);
PAINT MONO (2262 3087);
FORCEPROP 1 LAST PACK_TYPE 0402LF
J 0
(2450 3075);
DISPLAY 0.510638 (2450 3075);
DISPLAY INVISIBLE (2450 3075);
FORCEPROP 1 LAST WATTAGE 1/16W
J 2
(2300 3000);
DISPLAY 0.319149 (2300 3000);
DISPLAY INVISIBLE (2300 3000);
FORCEPROP 2 LAST CDS_LIB pure_quanta
J 0
(2200 3075);
DISPLAY INVISIBLE (2200 3075);
FORCEPROP 1 LAST PATH I337
J 0
(2150 3225);
DISPLAY 0.978723 (2150 3225);
PAINT WHITE (2150 3225);
DISPLAY INVISIBLE (2150 3225);
FORCEPROP 0 LAST CDS_LOCATION R3940
J 0
(2075 3125);
DISPLAY 1.021277 (2075 3125);
DISPLAY INVISIBLE (2075 3125);
FORCEPROP 0 LAST $SEC 1
J 0
(2075 3125);
DISPLAY 0.680851 (2075 3125);
PAINT MONO (2075 3125);
DISPLAY INVISIBLE (2075 3125);
FORCEPROP 0 LAST CDS_SEC 1
J 0
(2075 3125);
DISPLAY 1.021277 (2075 3125);
DISPLAY INVISIBLE (2075 3125);
FORCEADD Q_RES..1
(2200 2725);
FORCEPROP 1 LAST PART_NUMBER CS00002JB13
J 0
(2125 2675);
DISPLAY 0.319149 (2125 2675);
DISPLAY INVISIBLE (2125 2675);
FORCEPROP 1 LAST VALUE 0
J 2
(2350 2725);
DISPLAY 0.404255 (2350 2725);
FORCEPROP 1 LAST TOLERANCE 5%
J 0
(2375 2725);
DISPLAY 0.404255 (2375 2725);
FORCEPROP 1 LAST MATERIAL EMPTY
J 0
(2425 2725);
DISPLAY 0.404255 (2425 2725);
FORCEPROP 0 LAST ROOM1 E1S1_P12V_MAM_TIC_BOM2
J 0
(2000 2800);
DISPLAY 0.404255 (2000 2800);
FORCEPROP 1 LAST $LOCATION R3941
J 0
(2025 2725);
DISPLAY 0.510638 (2025 2725);
FORCEPROP 1 LASTPIN (2100 2725) $PN 1
J 0
(2112 2737);
DISPLAY 0.787234 (2112 2737);
PAINT MONO (2112 2737);
FORCEPROP 1 LASTPIN (2300 2725) $PN 2
J 0
(2262 2737);
DISPLAY 0.787234 (2262 2737);
PAINT MONO (2262 2737);
FORCEPROP 1 LAST PACK_TYPE 0402LF
J 0
(2450 2725);
DISPLAY 0.510638 (2450 2725);
DISPLAY INVISIBLE (2450 2725);
FORCEPROP 1 LAST WATTAGE 1/16W
J 2
(2300 2650);
DISPLAY 0.319149 (2300 2650);
DISPLAY INVISIBLE (2300 2650);
FORCEPROP 2 LAST CDS_LIB pure_quanta
J 0
(2200 2725);
DISPLAY INVISIBLE (2200 2725);
FORCEPROP 1 LAST PATH I338
J 0
(2150 2875);
DISPLAY 0.978723 (2150 2875);
PAINT WHITE (2150 2875);
DISPLAY INVISIBLE (2150 2875);
FORCEPROP 0 LAST CDS_LOCATION R3941
J 0
(2075 2775);
DISPLAY 1.021277 (2075 2775);
DISPLAY INVISIBLE (2075 2775);
FORCEPROP 0 LAST $SEC 1
J 0
(2075 2775);
DISPLAY 0.680851 (2075 2775);
PAINT MONO (2075 2775);
DISPLAY INVISIBLE (2075 2775);
FORCEPROP 0 LAST CDS_SEC 1
J 0
(2075 2775);
DISPLAY 1.021277 (2075 2775);
DISPLAY INVISIBLE (2075 2775);
FORCEADD Q_RES..1
(2200 2575);
FORCEPROP 1 LAST PART_NUMBER CS00002JB13
J 0
(2125 2525);
DISPLAY 0.319149 (2125 2525);
DISPLAY INVISIBLE (2125 2525);
FORCEPROP 1 LAST VALUE 0
J 2
(2350 2575);
DISPLAY 0.404255 (2350 2575);
FORCEPROP 1 LAST MATERIAL CHIP
J 0
(2425 2575);
DISPLAY 0.404255 (2425 2575);
PAINT RED (2425 2575);
FORCEPROP 0 LAST ROOM1 E1S1_P12V_MPS_TIC_BOM4
J 0
(2025 2500);
DISPLAY 0.404255 (2025 2500);
FORCEPROP 1 LAST TOLERANCE 5%
J 0
(2375 2575);
DISPLAY 0.404255 (2375 2575);
FORCEPROP 1 LAST $LOCATION R3942
J 0
(2025 2575);
DISPLAY 0.510638 (2025 2575);
FORCEPROP 1 LASTPIN (2100 2575) $PN 1
J 0
(2112 2587);
DISPLAY 0.787234 (2112 2587);
PAINT MONO (2112 2587);
FORCEPROP 1 LASTPIN (2300 2575) $PN 2
J 0
(2262 2587);
DISPLAY 0.787234 (2262 2587);
PAINT MONO (2262 2587);
FORCEPROP 1 LAST PACK_TYPE 0402LF
J 0
(2450 2575);
DISPLAY 0.510638 (2450 2575);
DISPLAY INVISIBLE (2450 2575);
FORCEPROP 1 LAST WATTAGE 1/16W
J 2
(2300 2500);
DISPLAY 0.319149 (2300 2500);
DISPLAY INVISIBLE (2300 2500);
FORCEPROP 2 LAST CDS_LIB pure_quanta
J 0
(2200 2575);
DISPLAY INVISIBLE (2200 2575);
FORCEPROP 1 LAST PATH I339
J 0
(2150 2725);
DISPLAY 0.978723 (2150 2725);
PAINT WHITE (2150 2725);
DISPLAY INVISIBLE (2150 2725);
FORCEPROP 0 LAST CDS_LOCATION R3942
J 0
(2075 2625);
DISPLAY 1.021277 (2075 2625);
DISPLAY INVISIBLE (2075 2625);
FORCEPROP 0 LAST $SEC 1
J 0
(2075 2625);
DISPLAY 0.680851 (2075 2625);
PAINT MONO (2075 2625);
DISPLAY INVISIBLE (2075 2625);
FORCEPROP 0 LAST CDS_SEC 1
J 0
(2075 2625);
DISPLAY 1.021277 (2075 2625);
DISPLAY INVISIBLE (2075 2625);
FORCEADD OFFPAGE..1
(1275 3075);
FORCEPROP 2 LAST $XR0 193 
J 0
(1023 3075);
DISPLAY 0.638298 (1023 3075);
PAINT MONO (1023 3075);
FORCEPROP 2 LAST CDS_LIB standard
J 0
(1275 3075);
DISPLAY INVISIBLE (1275 3075);
FORCEPROP 1 LAST OFFPAGE TRUE
J 0
(1600 2950);
DISPLAY 0.872340 (1600 2950);
PAINT GREEN (1600 2950);
DISPLAY INVISIBLE (1600 2950);
FORCEPROP 1 LAST COMMENT_BODY TRUE
J 0
(1400 2975);
DISPLAY 0.872340 (1400 2975);
PAINT GREEN (1400 2975);
DISPLAY INVISIBLE (1400 2975);
FORCEPROP 2 LAST PATH I340
J 0
(850 3125);
DISPLAY 1.021277 (850 3125);
DISPLAY INVISIBLE (850 3125);
FORCEADD OFFPAGE..1
(1275 2725);
FORCEPROP 2 LAST $XR0 192 
J 0
(1023 2725);
DISPLAY 0.638298 (1023 2725);
PAINT MONO (1023 2725);
FORCEPROP 2 LAST PATH I341
J 0
(850 2775);
DISPLAY 1.021277 (850 2775);
DISPLAY INVISIBLE (850 2775);
FORCEPROP 1 LAST COMMENT_BODY TRUE
J 0
(1400 2625);
DISPLAY 0.872340 (1400 2625);
PAINT GREEN (1400 2625);
DISPLAY INVISIBLE (1400 2625);
FORCEPROP 1 LAST OFFPAGE TRUE
J 0
(1600 2600);
DISPLAY 0.872340 (1600 2600);
PAINT GREEN (1600 2600);
DISPLAY INVISIBLE (1600 2600);
FORCEPROP 2 LAST CDS_LIB standard
J 0
(1275 2725);
DISPLAY INVISIBLE (1275 2725);
FORCEADD OFFPAGE..1
(1275 2575);
FORCEPROP 2 LAST $XR0 193 
J 0
(1023 2575);
DISPLAY 0.638298 (1023 2575);
PAINT MONO (1023 2575);
FORCEPROP 2 LAST PATH I342
J 0
(850 2625);
DISPLAY 1.021277 (850 2625);
DISPLAY INVISIBLE (850 2625);
FORCEPROP 2 LAST CDS_LIB standard
J 0
(1275 2575);
DISPLAY INVISIBLE (1275 2575);
FORCEPROP 1 LAST OFFPAGE TRUE
J 0
(1600 2450);
DISPLAY 0.872340 (1600 2450);
PAINT GREEN (1600 2450);
DISPLAY INVISIBLE (1600 2450);
FORCEPROP 1 LAST COMMENT_BODY TRUE
J 0
(1400 2475);
DISPLAY 0.872340 (1400 2475);
PAINT GREEN (1400 2475);
DISPLAY INVISIBLE (1400 2475);
FORCEADD OFFPAGE..1
R 2
(6750 4050);
FORCEPROP 2 LAST $XR0 250 
J 0
(6936 4050);
DISPLAY 0.638298 (6936 4050);
PAINT MONO (6936 4050);
FORCEPROP 1 LAST COMMENT_BODY TRUE
J 2
(6625 3950);
DISPLAY 0.872340 (6625 3950);
PAINT GREEN (6625 3950);
DISPLAY INVISIBLE (6625 3950);
FORCEPROP 1 LAST OFFPAGE TRUE
J 2
(6425 3925);
DISPLAY 0.872340 (6425 3925);
PAINT GREEN (6425 3925);
DISPLAY INVISIBLE (6425 3925);
FORCEPROP 2 LAST CDS_LIB standard
J 2
(6750 4050);
DISPLAY INVISIBLE (6750 4050);
FORCEPROP 2 LAST PATH I343
J 0
(6950 4100);
DISPLAY 1.021277 (6950 4100);
DISPLAY INVISIBLE (6950 4100);
FORCEADD OFFPAGE..4
R 2
(5150 1225);
FORCEPROP 2 LAST $XR0 250 
J 0
(4898 1225);
DISPLAY 0.638298 (4898 1225);
PAINT MONO (4898 1225);
FORCEPROP 1 LAST COMMENT_BODY TRUE
J 2
(5175 1125);
DISPLAY 0.872340 (5175 1125);
PAINT GREEN (5175 1125);
DISPLAY INVISIBLE (5175 1125);
FORCEPROP 1 LAST OFFPAGE TRUE
J 2
(4825 1100);
DISPLAY 0.872340 (4825 1100);
DISPLAY INVISIBLE (4825 1100);
FORCEPROP 2 LAST CDS_LIB standard
J 2
(5150 1225);
DISPLAY INVISIBLE (5150 1225);
FORCEPROP 2 LAST PATH I344
J 0
(4900 1275);
DISPLAY 1.021277 (4900 1275);
DISPLAY INVISIBLE (4900 1275);
FORCEADD Q_RES..2
(-475 150);
FORCEPROP 1 LAST PART_NUMBER CS24702FB06
J 0
(-435 25);
DISPLAY 0.638298 (-435 25);
DISPLAY INVISIBLE (-435 25);
FORCEPROP 1 LAST PACK_TYPE 0402LF
J 0
(-435 -25);
DISPLAY 0.638298 (-435 -25);
FORCEPROP 1 LAST TOLERANCE 1%
J 0
(-430 175);
DISPLAY 0.638298 (-430 175);
FORCEPROP 1 LAST VALUE 4.7K
J 0
(-430 225);
DISPLAY 0.638298 (-430 225);
FORCEPROP 1 LAST WATTAGE 1/16W
J 0
(-435 125);
DISPLAY 0.638298 (-435 125);
FORCEPROP 1 LAST MATERIAL CHIP
J 0
(-425 75);
DISPLAY 0.638298 (-425 75);
FORCEPROP 1 LAST $LOCATION R4568
J 0
(-430 275);
DISPLAY 0.638298 (-430 275);
FORCEPROP 1 LASTPIN (-475 250) $PN 1
J 0
(-470 212);
DISPLAY 0.787234 (-470 212);
PAINT MONO (-470 212);
FORCEPROP 1 LASTPIN (-475 50) $PN 2
J 0
(-470 60);
DISPLAY 0.787234 (-470 60);
PAINT MONO (-470 60);
FORCEPROP 2 LAST CDS_LIB pure_quanta
J 0
(-475 150);
DISPLAY INVISIBLE (-475 150);
FORCEPROP 1 LAST PATH I346
J 0
(-425 325);
DISPLAY 0.978723 (-425 325);
PAINT WHITE (-425 325);
DISPLAY INVISIBLE (-425 325);
FORCEPROP 0 LAST CDS_LOCATION R4568
J 0
(-425 325);
DISPLAY 1.021277 (-425 325);
DISPLAY INVISIBLE (-425 325);
FORCEPROP 0 LAST $SEC 1
J 0
(-425 325);
DISPLAY 0.680851 (-425 325);
PAINT MONO (-425 325);
DISPLAY INVISIBLE (-425 325);
FORCEPROP 0 LAST CDS_SEC 1
J 0
(-425 325);
DISPLAY 1.021277 (-425 325);
DISPLAY INVISIBLE (-425 325);
FORCEADD UNIVERSAL_GND..1
(-475 -75);
FORCEPROP 3 LASTPIN (-475 -25) SIG_NAME GND\g
J 0
(-465 -15);
DISPLAY 0.659574 (-465 -15);
PAINT MONO (-465 -15);
DISPLAY INVISIBLE (-465 -15);
FORCEPROP 2 LAST CDS_LIB logical_power
J 0
(-475 -75);
DISPLAY INVISIBLE (-475 -75);
FORCEPROP 1 LAST PATH I347
J 0
(-400 -75);
DISPLAY 0.872340 (-400 -75);
PAINT AQUA (-400 -75);
DISPLAY INVISIBLE (-400 -75);
FORCEPROP 1 LAST HDL_POWER GND
J 1
(-450 -150);
DISPLAY 0.872340 (-450 -150);
PAINT GREEN (-450 -150);
DISPLAY INVISIBLE (-450 -150);
FORCEADD Q_RES..2
(-475 525);
FORCEPROP 1 LAST PART_NUMBER CS25112FB04
J 0
(-435 400);
DISPLAY 0.638298 (-435 400);
DISPLAY INVISIBLE (-435 400);
FORCEPROP 1 LAST WATTAGE 1/16W
J 0
(-435 500);
DISPLAY 0.638298 (-435 500);
FORCEPROP 1 LAST TOLERANCE 1%
J 0
(-430 550);
DISPLAY 0.638298 (-430 550);
FORCEPROP 1 LAST MATERIAL CHIP
J 0
(-435 450);
DISPLAY 0.638298 (-435 450);
FORCEPROP 1 LAST PACK_TYPE 0402LF
J 0
(-435 350);
DISPLAY 0.638298 (-435 350);
FORCEPROP 1 LAST VALUE 5.11K
J 0
(-430 600);
DISPLAY 0.638298 (-430 600);
FORCEPROP 1 LAST $LOCATION R4567
J 0
(-430 650);
DISPLAY 0.638298 (-430 650);
FORCEPROP 1 LASTPIN (-475 625) $PN 1
J 0
(-470 587);
DISPLAY 0.787234 (-470 587);
PAINT MONO (-470 587);
FORCEPROP 1 LASTPIN (-475 425) $PN 2
J 0
(-470 435);
DISPLAY 0.787234 (-470 435);
PAINT MONO (-470 435);
FORCEPROP 1 LAST PATH I348
J 0
(-425 700);
DISPLAY 0.978723 (-425 700);
PAINT WHITE (-425 700);
DISPLAY INVISIBLE (-425 700);
FORCEPROP 2 LAST CDS_LIB pure_quanta
J 0
(-475 525);
DISPLAY INVISIBLE (-475 525);
FORCEPROP 0 LAST CDS_LOCATION R4567
J 0
(-425 700);
DISPLAY 1.021277 (-425 700);
DISPLAY INVISIBLE (-425 700);
FORCEPROP 0 LAST $SEC 1
J 0
(-425 700);
DISPLAY 0.680851 (-425 700);
PAINT MONO (-425 700);
DISPLAY INVISIBLE (-425 700);
FORCEPROP 0 LAST CDS_SEC 1
J 0
(-425 700);
DISPLAY 1.021277 (-425 700);
DISPLAY INVISIBLE (-425 700);
FORCEADD MAX11617EEET..1
(5475 4100);
FORCEPROP 1 LAST PART_NUMBER AL011617W00
J 0
(5230 4634);
DISPLAY 0.723404 (5230 4634);
PAINT GREEN (5230 4634);
DISPLAY INVISIBLE (5230 4634);
FORCEPROP 2 LAST ROOM ADC1_BOM1
J 0
(5250 4925);
DISPLAY 1.021277 (5250 4925);
FORCEPROP 2 LAST VALUE MAX11617EEE+T
J 0
(5250 4825);
DISPLAY 1.021277 (5250 4825);
FORCEPROP 2 LAST PART_TYPE SMLF
J 0
(5250 4875);
DISPLAY 1.021277 (5250 4875);
FORCEPROP 1 LAST MATERIAL EMPTY
J 0
(5230 4507);
DISPLAY 0.723404 (5230 4507);
PAINT GREEN (5230 4507);
FORCEPROP 1 LAST $LOCATION U193
J 0
(5230 4781);
DISPLAY 0.723404 (5230 4781);
PAINT GREEN (5230 4781);
FORCEPROP 2 LASTPIN (5075 4050) $PN 5
J 2
(5065 4060);
DISPLAY 0.680851 (5065 4060);
PAINT MONO (5065 4060);
FORCEPROP 2 LASTPIN (5075 3950) $PN 6
J 2
(5065 3960);
DISPLAY 0.680851 (5065 3960);
PAINT MONO (5065 3960);
FORCEPROP 2 LASTPIN (5075 3850) $PN 7
J 2
(5065 3860);
DISPLAY 0.680851 (5065 3860);
PAINT MONO (5065 3860);
FORCEPROP 2 LASTPIN (5075 3750) $PN 8
J 2
(5065 3760);
DISPLAY 0.680851 (5065 3760);
PAINT MONO (5065 3760);
FORCEPROP 2 LASTPIN (5875 3750) $PN 9
J 0
(5885 3760);
DISPLAY 0.680851 (5885 3760);
PAINT MONO (5885 3760);
FORCEPROP 2 LASTPIN (5875 3850) $PN 10
J 0
(5885 3860);
DISPLAY 0.680851 (5885 3860);
PAINT MONO (5885 3860);
FORCEPROP 2 LASTPIN (5875 3950) $PN 11
J 0
(5885 3960);
DISPLAY 0.680851 (5885 3960);
PAINT MONO (5885 3960);
FORCEPROP 2 LASTPIN (5875 4050) $PN 12
J 0
(5885 4060);
DISPLAY 0.680851 (5885 4060);
PAINT MONO (5885 4060);
FORCEPROP 2 LASTPIN (5075 4150) $PN 4
J 2
(5065 4160);
DISPLAY 0.680851 (5065 4160);
PAINT MONO (5065 4160);
FORCEPROP 2 LASTPIN (5075 4250) $PN 3
J 2
(5065 4260);
DISPLAY 0.680851 (5065 4260);
PAINT MONO (5065 4260);
FORCEPROP 2 LASTPIN (5075 4350) $PN 2
J 2
(5065 4360);
DISPLAY 0.680851 (5065 4360);
PAINT MONO (5065 4360);
FORCEPROP 2 LASTPIN (5075 4450) $PN 1
J 2
(5065 4460);
DISPLAY 0.680851 (5065 4460);
PAINT MONO (5065 4460);
FORCEPROP 2 LASTPIN (5875 4350) $PN 15
J 0
(5885 4360);
DISPLAY 0.680851 (5885 4360);
PAINT MONO (5885 4360);
FORCEPROP 2 LASTPIN (5875 4150) $PN 13
J 0
(5885 4160);
DISPLAY 0.680851 (5885 4160);
PAINT MONO (5885 4160);
FORCEPROP 2 LASTPIN (5875 4250) $PN 14
J 0
(5885 4260);
DISPLAY 0.680851 (5885 4260);
PAINT MONO (5885 4260);
FORCEPROP 2 LASTPIN (5875 4450) $PN 16
J 0
(5885 4460);
DISPLAY 0.680851 (5885 4460);
PAINT MONO (5885 4460);
FORCEPROP 2 LAST CDS_LIB pure_quanta
J 0
(5475 4100);
DISPLAY INVISIBLE (5475 4100);
FORCEPROP 1 LAST PATH I57
J 0
(5475 4100);
DISPLAY 0.723404 (5475 4100);
PAINT GREEN (5475 4100);
DISPLAY INVISIBLE (5475 4100);
FORCEPROP 1 LAST NEEDS_NO_SIZE TRUE
J 0
(5475 4100);
DISPLAY 0.723404 (5475 4100);
PAINT GREEN (5475 4100);
DISPLAY INVISIBLE (5475 4100);
FORCEPROP 1 LAST CDS_LMAN_SYM_OUTLINE -250,400,250,-400
J 0
(5475 4100);
DISPLAY 0.468085 (5475 4100);
PAINT GREEN (5475 4100);
DISPLAY INVISIBLE (5475 4100);
FORCEPROP 2 LAST SEC_TYPE 
J 0
(5250 4925);
DISPLAY 1.021277 (5250 4925);
DISPLAY INVISIBLE (5250 4925);
FORCEPROP 2 LAST CDS_LOCATION U193
J 0
(5250 4925);
DISPLAY 1.021277 (5250 4925);
DISPLAY INVISIBLE (5250 4925);
FORCEPROP 2 LAST SEC 1
J 0
(5250 4925);
DISPLAY 0.680851 (5250 4925);
PAINT MONO (5250 4925);
DISPLAY INVISIBLE (5250 4925);
FORCEADD Q_CAP..1
R 2
(6400 4525);
FORCEPROP 1 LAST PART_NUMBER CH4104K1B00
J 2
(6700 4400);
DISPLAY 0.510638 (6700 4400);
DISPLAY INVISIBLE (6700 4400);
FORCEPROP 1 LAST VALUE 0.1UF
J 2
(6575 4600);
DISPLAY 0.510638 (6575 4600);
FORCEPROP 1 LAST VOLTAGE 25V
J 2
(6550 4550);
DISPLAY 0.510638 (6550 4550);
FORCEPROP 1 LAST TOLERANCE 10%
J 2
(6550 4500);
DISPLAY 0.510638 (6550 4500);
FORCEPROP 1 LAST MATERIAL EMPTY
J 2
(6550 4450);
DISPLAY 0.510638 (6550 4450);
FORCEPROP 1 LAST PACK_TYPE 0402
J 2
(6575 4350);
DISPLAY 0.510638 (6575 4350);
FORCEPROP 2 LAST ROOM ADC1_BOM1
J 0
(6475 4700);
DISPLAY 0.510638 (6475 4700);
FORCEPROP 1 LAST $LOCATION C1757
J 2
(6575 4650);
DISPLAY 0.638298 (6575 4650);
FORCEPROP 1 LASTPIN (6400 4625) $PN 1
J 2
(6390 4605);
DISPLAY 0.787234 (6390 4605);
PAINT MONO (6390 4605);
FORCEPROP 1 LASTPIN (6400 4425) $PN 2
J 2
(6390 4405);
DISPLAY 0.787234 (6390 4405);
PAINT MONO (6390 4405);
FORCEPROP 1 LAST PATH I58
J 2
(6350 4675);
DISPLAY 0.978723 (6350 4675);
PAINT WHITE (6350 4675);
DISPLAY INVISIBLE (6350 4675);
FORCEPROP 2 LAST CDS_LIB pure_quanta
J 0
(6400 4525);
DISPLAY INVISIBLE (6400 4525);
FORCEPROP 0 LAST CDS_LOCATION C1757
J 0
(6350 4675);
DISPLAY 1.021277 (6350 4675);
DISPLAY INVISIBLE (6350 4675);
FORCEPROP 0 LAST $SEC 1
J 0
(6350 4675);
DISPLAY 0.680851 (6350 4675);
PAINT MONO (6350 4675);
DISPLAY INVISIBLE (6350 4675);
FORCEPROP 0 LAST CDS_SEC 1
J 0
(6350 4675);
DISPLAY 1.021277 (6350 4675);
DISPLAY INVISIBLE (6350 4675);
FORCEADD UNIVERSAL_GND..1
(6400 4350);
FORCEPROP 3 LASTPIN (6400 4400) SIG_NAME GND\g
J 0
(6410 4410);
DISPLAY 0.659574 (6410 4410);
PAINT MONO (6410 4410);
DISPLAY INVISIBLE (6410 4410);
FORCEPROP 2 LAST CDS_LIB logical_power
J 0
(6400 4350);
DISPLAY INVISIBLE (6400 4350);
FORCEPROP 1 LAST HDL_POWER GND
J 1
(6425 4275);
DISPLAY 0.872340 (6425 4275);
PAINT GREEN (6425 4275);
DISPLAY INVISIBLE (6425 4275);
FORCEPROP 1 LAST PATH I60
J 0
(6475 4350);
DISPLAY 0.872340 (6475 4350);
PAINT AQUA (6475 4350);
DISPLAY INVISIBLE (6475 4350);
FORCEADD Q_CAP..1
(6775 4525);
FORCEPROP 1 LAST PART_NUMBER CH6103KEA00
J 0
(6825 4375);
DISPLAY 0.510638 (6825 4375);
DISPLAY INVISIBLE (6825 4375);
FORCEPROP 1 LAST PACK_TYPE C0805
J 0
(6825 4325);
DISPLAY 0.510638 (6825 4325);
FORCEPROP 1 LAST VALUE 10UF
J 0
(6825 4575);
DISPLAY 0.510638 (6825 4575);
FORCEPROP 1 LAST VOLTAGE 16V
J 0
(6825 4525);
DISPLAY 0.510638 (6825 4525);
FORCEPROP 1 LAST TOLERANCE 10%
J 0
(6825 4475);
DISPLAY 0.510638 (6825 4475);
FORCEPROP 1 LAST MATERIAL EMPTY
J 0
(6825 4425);
DISPLAY 0.510638 (6825 4425);
FORCEPROP 2 LAST ROOM ADC1_BOM1
J 0
(6825 4650);
DISPLAY 0.510638 (6825 4650);
FORCEPROP 1 LAST $LOCATION C1768
J 0
(6825 4625);
DISPLAY 0.510638 (6825 4625);
FORCEPROP 1 LASTPIN (6775 4625) $PN 1
J 0
(6785 4605);
DISPLAY 0.787234 (6785 4605);
FORCEPROP 1 LASTPIN (6775 4425) $PN 2
J 0
(6785 4405);
DISPLAY 0.787234 (6785 4405);
FORCEPROP 2 LAST CDS_LIB pure_quanta
J 0
(6775 4525);
PAINT MONO (6775 4525);
DISPLAY INVISIBLE (6775 4525);
FORCEPROP 1 LAST PATH I61
J 0
(6825 4675);
DISPLAY 0.978723 (6825 4675);
PAINT WHITE (6825 4675);
DISPLAY INVISIBLE (6825 4675);
FORCEPROP 2 LAST CDS_LOCATION C1768
J 0
(6825 4725);
DISPLAY 1.021277 (6825 4725);
DISPLAY INVISIBLE (6825 4725);
FORCEPROP 2 LAST $SEC 1
J 0
(6825 4725);
DISPLAY 0.680851 (6825 4725);
PAINT MONO (6825 4725);
DISPLAY INVISIBLE (6825 4725);
FORCEPROP 2 LAST CDS_SEC 1
J 0
(6825 4725);
DISPLAY 1.021277 (6825 4725);
DISPLAY INVISIBLE (6825 4725);
FORCEADD Q_INDUCTOR..1
(7100 4750);
FORCEPROP 1 LAST PART_NUMBER TMP_QCX8PG300001
J 0
(7000 4860);
DISPLAY 0.382979 (7000 4860);
PAINT GREEN (7000 4860);
DISPLAY INVISIBLE (7000 4860);
FORCEPROP 2 LAST PACK_TYPE SMLF
J 0
(7000 4950);
DISPLAY 0.510638 (7000 4950);
FORCEPROP 1 LAST MATERIAL EMPTY
J 0
(7000 4805);
DISPLAY 0.382979 (7000 4805);
PAINT GREEN (7000 4805);
FORCEPROP 2 LAST VALUE BLM18PG300SN1D 
J 0
(7000 5000);
DISPLAY 0.510638 (7000 5000);
FORCEPROP 2 LAST ROOM ADC1_BOM1
J 0
(7000 5025);
DISPLAY 0.638298 (7000 5025);
FORCEPROP 1 LAST $LOCATION L15
J 0
(7000 4910);
DISPLAY 0.382979 (7000 4910);
PAINT GREEN (7000 4910);
FORCEPROP 2 LASTPIN (7000 4725) $PN 1
J 2
(6990 4735);
DISPLAY 0.680851 (6990 4735);
PAINT MONO (6990 4735);
FORCEPROP 2 LASTPIN (7200 4725) $PN 2
J 0
(7210 4735);
DISPLAY 0.680851 (7210 4735);
PAINT MONO (7210 4735);
FORCEPROP 1 LAST NEEDS_NO_SIZE TRUE
J 0
(7100 4750);
DISPLAY 0.468085 (7100 4750);
PAINT GREEN (7100 4750);
DISPLAY INVISIBLE (7100 4750);
FORCEPROP 1 LAST PATH I62
J 0
(7175 4805);
DISPLAY 0.723404 (7175 4805);
PAINT GREEN (7175 4805);
DISPLAY INVISIBLE (7175 4805);
FORCEPROP 2 LAST CDS_LIB pure_quanta
J 0
(7100 4750);
DISPLAY INVISIBLE (7100 4750);
FORCEPROP 2 LAST CDS_LOCATION L15
J 0
(7000 5025);
DISPLAY 1.021277 (7000 5025);
DISPLAY INVISIBLE (7000 5025);
FORCEPROP 2 LAST $SEC 1
J 0
(7000 5025);
DISPLAY 0.680851 (7000 5025);
PAINT MONO (7000 5025);
DISPLAY INVISIBLE (7000 5025);
FORCEPROP 2 LAST CDS_SEC 1
J 0
(7000 5025);
DISPLAY 1.021277 (7000 5025);
DISPLAY INVISIBLE (7000 5025);
FORCEADD UNIVERSAL_POWER..1
(7525 4950);
FORCEPROP 3 LASTPIN (7525 4900) SIG_NAME P3V3_AUX\g
J 0
(7535 4910);
DISPLAY 0.659574 (7535 4910);
PAINT MONO (7535 4910);
DISPLAY INVISIBLE (7535 4910);
FORCEPROP 1 LAST HDL_POWER P3V3_AUX
J 1
(7525 5000);
DISPLAY 0.872340 (7525 5000);
PAINT GREEN (7525 5000);
FORCEPROP 1 LAST PATH I63
J 0
(7575 4975);
DISPLAY 0.872340 (7575 4975);
PAINT AQUA (7575 4975);
DISPLAY INVISIBLE (7575 4975);
FORCEPROP 2 LAST CDS_LIB logical_power
J 0
(7525 4950);
DISPLAY INVISIBLE (7525 4950);
FORCEADD UNIVERSAL_GND..1
(6775 4350);
FORCEPROP 3 LASTPIN (6775 4400) SIG_NAME GND\g
J 0
(6785 4410);
DISPLAY 0.659574 (6785 4410);
PAINT MONO (6785 4410);
DISPLAY INVISIBLE (6785 4410);
FORCEPROP 2 LAST CDS_LIB logical_power
J 0
(6775 4350);
DISPLAY INVISIBLE (6775 4350);
FORCEPROP 1 LAST HDL_POWER GND
J 1
(6800 4275);
DISPLAY 0.872340 (6800 4275);
PAINT GREEN (6800 4275);
DISPLAY INVISIBLE (6800 4275);
FORCEPROP 1 LAST PATH I64
J 0
(6850 4350);
DISPLAY 0.872340 (6850 4350);
PAINT AQUA (6850 4350);
DISPLAY INVISIBLE (6850 4350);
FORCEADD Q_CAP..1
(4075 4550);
FORCEPROP 1 LAST PART_NUMBER CH6103KEA00
J 0
(4125 4400);
DISPLAY 0.510638 (4125 4400);
DISPLAY INVISIBLE (4125 4400);
FORCEPROP 1 LAST MATERIAL EMPTY
J 0
(4125 4450);
DISPLAY 0.510638 (4125 4450);
FORCEPROP 1 LAST VOLTAGE 16V
J 0
(4125 4550);
DISPLAY 0.510638 (4125 4550);
FORCEPROP 2 LAST ROOM ADC1_BOM1
J 0
(4125 4675);
DISPLAY 0.510638 (4125 4675);
FORCEPROP 1 LAST PACK_TYPE C0805
J 0
(4125 4350);
DISPLAY 0.510638 (4125 4350);
FORCEPROP 1 LAST TOLERANCE 10%
J 0
(4125 4500);
DISPLAY 0.510638 (4125 4500);
FORCEPROP 1 LAST VALUE 10UF
J 0
(4125 4600);
DISPLAY 0.510638 (4125 4600);
FORCEPROP 1 LAST $LOCATION C1767
J 0
(4125 4625);
DISPLAY 0.510638 (4125 4625);
FORCEPROP 1 LASTPIN (4075 4650) $PN 1
J 0
(4085 4630);
DISPLAY 0.787234 (4085 4630);
FORCEPROP 1 LASTPIN (4075 4450) $PN 2
J 0
(4085 4430);
DISPLAY 0.787234 (4085 4430);
FORCEPROP 2 LAST CDS_LIB pure_quanta
J 0
(4075 4550);
PAINT MONO (4075 4550);
DISPLAY INVISIBLE (4075 4550);
FORCEPROP 1 LAST PATH I68
J 0
(4125 4700);
DISPLAY 0.978723 (4125 4700);
PAINT WHITE (4125 4700);
DISPLAY INVISIBLE (4125 4700);
FORCEPROP 2 LAST CDS_LOCATION C1767
J 0
(4125 4750);
DISPLAY 1.021277 (4125 4750);
DISPLAY INVISIBLE (4125 4750);
FORCEPROP 2 LAST $SEC 1
J 0
(4125 4750);
DISPLAY 0.680851 (4125 4750);
PAINT MONO (4125 4750);
DISPLAY INVISIBLE (4125 4750);
FORCEPROP 2 LAST CDS_SEC 1
J 0
(4125 4750);
DISPLAY 1.021277 (4125 4750);
DISPLAY INVISIBLE (4125 4750);
FORCEADD UNIVERSAL_GND..1
(4075 4350);
FORCEPROP 3 LASTPIN (4075 4400) SIG_NAME GND\g
J 0
(4085 4410);
DISPLAY 0.659574 (4085 4410);
PAINT MONO (4085 4410);
DISPLAY INVISIBLE (4085 4410);
FORCEPROP 1 LAST PATH I69
J 0
(4150 4350);
DISPLAY 0.872340 (4150 4350);
PAINT AQUA (4150 4350);
DISPLAY INVISIBLE (4150 4350);
FORCEPROP 2 LAST CDS_LIB logical_power
J 0
(4075 4350);
DISPLAY INVISIBLE (4075 4350);
FORCEPROP 1 LAST HDL_POWER GND
J 1
(4100 4275);
DISPLAY 0.872340 (4100 4275);
PAINT GREEN (4100 4275);
DISPLAY INVISIBLE (4100 4275);
FORCEADD Q_CAP..1
R 2
(3700 4550);
FORCEPROP 1 LAST PART_NUMBER CH4104K1B00
J 2
(4000 4425);
DISPLAY 0.510638 (4000 4425);
DISPLAY INVISIBLE (4000 4425);
FORCEPROP 1 LAST VALUE 0.1UF
J 2
(3875 4625);
DISPLAY 0.510638 (3875 4625);
FORCEPROP 1 LAST PACK_TYPE 0402
J 2
(3875 4375);
DISPLAY 0.510638 (3875 4375);
FORCEPROP 1 LAST TOLERANCE 10%
J 2
(3850 4525);
DISPLAY 0.510638 (3850 4525);
FORCEPROP 1 LAST VOLTAGE 25V
J 2
(3850 4575);
DISPLAY 0.510638 (3850 4575);
FORCEPROP 1 LAST MATERIAL EMPTY
J 2
(3850 4475);
DISPLAY 0.510638 (3850 4475);
FORCEPROP 2 LAST ROOM ADC1_BOM1
J 0
(3775 4325);
DISPLAY 0.510638 (3775 4325);
FORCEPROP 1 LAST $LOCATION C1347
J 2
(3875 4675);
DISPLAY 0.638298 (3875 4675);
FORCEPROP 1 LASTPIN (3700 4650) $PN 1
J 2
(3690 4630);
DISPLAY 0.787234 (3690 4630);
PAINT MONO (3690 4630);
FORCEPROP 1 LASTPIN (3700 4450) $PN 2
J 2
(3690 4430);
DISPLAY 0.787234 (3690 4430);
PAINT MONO (3690 4430);
FORCEPROP 2 LAST CDS_LIB pure_quanta
J 0
(3700 4550);
DISPLAY INVISIBLE (3700 4550);
FORCEPROP 1 LAST PATH I70
J 2
(3650 4700);
DISPLAY 0.978723 (3650 4700);
PAINT WHITE (3650 4700);
DISPLAY INVISIBLE (3650 4700);
FORCEPROP 0 LAST CDS_LOCATION C1347
J 0
(3650 4700);
DISPLAY 1.021277 (3650 4700);
DISPLAY INVISIBLE (3650 4700);
FORCEPROP 0 LAST $SEC 1
J 0
(3650 4700);
DISPLAY 0.680851 (3650 4700);
PAINT MONO (3650 4700);
DISPLAY INVISIBLE (3650 4700);
FORCEPROP 0 LAST CDS_SEC 1
J 0
(3650 4700);
DISPLAY 1.021277 (3650 4700);
DISPLAY INVISIBLE (3650 4700);
FORCEADD UNIVERSAL_GND..1
(3700 4350);
FORCEPROP 3 LASTPIN (3700 4400) SIG_NAME GND\g
J 0
(3710 4410);
DISPLAY 0.659574 (3710 4410);
PAINT MONO (3710 4410);
DISPLAY INVISIBLE (3710 4410);
FORCEPROP 1 LAST HDL_POWER GND
J 1
(3725 4275);
DISPLAY 0.872340 (3725 4275);
PAINT GREEN (3725 4275);
DISPLAY INVISIBLE (3725 4275);
FORCEPROP 1 LAST PATH I71
J 0
(3775 4350);
DISPLAY 0.872340 (3775 4350);
PAINT AQUA (3775 4350);
DISPLAY INVISIBLE (3775 4350);
FORCEPROP 2 LAST CDS_LIB logical_power
J 0
(3700 4350);
DISPLAY INVISIBLE (3700 4350);
FORCEADD Q_RES..1
(4425 4725);
FORCEPROP 1 LAST PART_NUMBER CS22002FB07
J 0
(4250 4825);
DISPLAY 0.638298 (4250 4825);
DISPLAY INVISIBLE (4250 4825);
FORCEPROP 1 LAST MATERIAL EMPTY
J 0
(4700 4725);
DISPLAY 0.638298 (4700 4725);
FORCEPROP 1 LAST VALUE 2K
J 2
(4600 4725);
DISPLAY 0.638298 (4600 4725);
FORCEPROP 1 LAST PACK_TYPE 0402LF
J 0
(4250 4875);
DISPLAY 0.638298 (4250 4875);
FORCEPROP 2 LAST ROOM ADC1_BOM1
J 0
(4550 4625);
DISPLAY 0.638298 (4550 4625);
FORCEPROP 1 LAST TOLERANCE 1%
J 0
(4625 4725);
DISPLAY 0.638298 (4625 4725);
FORCEPROP 1 LAST WATTAGE 1/16W
J 2
(4625 4875);
DISPLAY 0.638298 (4625 4875);
FORCEPROP 1 LAST $LOCATION R2900
J 0
(4175 4725);
DISPLAY 0.638298 (4175 4725);
FORCEPROP 1 LASTPIN (4325 4725) $PN 1
J 0
(4337 4737);
DISPLAY 0.787234 (4337 4737);
FORCEPROP 1 LASTPIN (4525 4725) $PN 2
J 0
(4487 4737);
DISPLAY 0.787234 (4487 4737);
FORCEPROP 1 LAST PATH I72
J 0
(4375 4875);
DISPLAY 0.978723 (4375 4875);
PAINT WHITE (4375 4875);
DISPLAY INVISIBLE (4375 4875);
FORCEPROP 2 LAST CDS_LIB pure_quanta
J 0
(4425 4725);
PAINT MONO (4425 4725);
DISPLAY INVISIBLE (4425 4725);
FORCEPROP 2 LAST CDS_LOCATION R2900
J 0
(4625 4925);
DISPLAY 1.021277 (4625 4925);
DISPLAY INVISIBLE (4625 4925);
FORCEPROP 2 LAST $SEC 1
J 0
(4625 4925);
DISPLAY 0.680851 (4625 4925);
PAINT MONO (4625 4925);
DISPLAY INVISIBLE (4625 4925);
FORCEPROP 2 LAST CDS_SEC 1
J 0
(4625 4925);
DISPLAY 1.021277 (4625 4925);
DISPLAY INVISIBLE (4625 4925);
FORCEADD QUANTA_TITLE_BLOCK_C..1
(7825 -825);
FORCEPROP 0 LAST CDS_CON_LAST_MODIFIED Fri Aug 25 14:04:20 2023
J 0
(5940 -810);
DISPLAY INVISIBLE (5940 -810);
FORCEPROP 1 LAST CUSTOM_TXT_CDS <CON_LAST_MODIFIED>
J 0
(5940 -810);
DISPLAY 0.978723 (5940 -810);
FORCEPROP 2 LAST CUSTOM_TXT_CDS <XR_PAGE_TITLE>
J 0
(-65 4425);
DISPLAY 0.638298 (-65 4425);
PAINT PINK (-65 4425);
DISPLAY INVISIBLE (-65 4425);
FORCEPROP 1 LAST CUSTOM_TXT_CDS <NAME_2>
J 0
(4650 -775);
FORCEPROP 1 LAST CUSTOM_TXT_CDS <NAME_1>
J 0
(4650 -650);
FORCEPROP 1 LAST CUSTOM_TXT_CDS <Q_NUMBER>
J 0
(6422 -722);
DISPLAY 1.212766 (6422 -722);
FORCEPROP 1 LAST CUSTOM_TXT_CDS <Q_PROJ>
J 0
(5443 -723);
DISPLAY 1.212766 (5443 -723);
FORCEPROP 1 LAST CUSTOM_TXT_CDS <Q_REV>
J 0
(7641 -722);
DISPLAY 1.212766 (7641 -722);
FORCEPROP 1 LAST CUSTOM_TXT_CDS <CON_PAGE_NUM> OF <CON_TOTAL_PAGES>
J 0
(7379 -807);
DISPLAY 0.978723 (7379 -807);
FORCEPROP 1 LAST Q_TITLE VOLTAGE SENSOR (1/2)
J 0
(-1541 -799);
DISPLAY 2.446809 (-1541 -799);
PAINT GREEN (-1541 -799);
FORCEPROP 1 LAST Q_DEPT 
J 1
(4062 -776);
DISPLAY 1.957447 (4062 -776);
PAINT GREEN (4062 -776);
FORCEPROP 2 LAST CDS_XR_PAGE_TITLE CR-250 : @S9S_MB_2U_LIB.S9S_MB_2U(SCH_1):PAGE250
J 0
(-65 4425);
DISPLAY 0.638298 (-65 4425);
PAINT PINK (-65 4425);
DISPLAY INVISIBLE (-65 4425);
FORCEPROP 2 LAST PAGE_BORDER TRUE
J 0
(-65 4425);
DISPLAY 0.638298 (-65 4425);
PAINT PINK (-65 4425);
DISPLAY INVISIBLE (-65 4425);
FORCEPROP 1 LAST COMMENT_BODY TRUE
J 0
(7837 -838);
DISPLAY 0.978723 (7837 -838);
PAINT GREEN (7837 -838);
DISPLAY INVISIBLE (7837 -838);
FORCEPROP 1 LAST CDS_LMAN_SYM_OUTLINE -9475,6775,100,-125
J 0
(7825 -825);
DISPLAY 0.468085 (7825 -825);
PAINT GREEN (7825 -825);
DISPLAY INVISIBLE (7825 -825);
FORCEPROP 2 LAST CDS_LIB pure_quanta
J 0
(7825 -825);
DISPLAY INVISIBLE (7825 -825);
FORCEADD DNS..2
(2225 2725);
PAINT RED (2225 2725);
FORCEPROP 1 LAST COMMENT_BODY TRUE
J 0
(2225 2725);
DISPLAY INVISIBLE (2225 2725);
FORCEPROP 2 LAST CDS_LIB mstr_misc
J 0
(2225 2725);
DISPLAY INVISIBLE (2225 2725);
FORCEADD DNS..2
(2250 3725);
PAINT RED (2250 3725);
FORCEPROP 1 LAST COMMENT_BODY TRUE
J 0
(2250 3725);
DISPLAY INVISIBLE (2250 3725);
FORCEPROP 2 LAST CDS_LIB mstr_misc
J 0
(2250 3725);
DISPLAY INVISIBLE (2250 3725);
FORCEADD DNS..2
(2275 4700);
PAINT RED (2275 4700);
FORCEPROP 2 LAST CDS_LIB mstr_misc
J 0
(2275 4700);
DISPLAY INVISIBLE (2275 4700);
FORCEPROP 1 LAST COMMENT_BODY TRUE
J 0
(2275 4700);
DISPLAY INVISIBLE (2275 4700);
FORCEADD DNS..2
(7125 4750);
PAINT RED (7125 4750);
FORCEPROP 1 LAST COMMENT_BODY TRUE
J 0
(7125 4750);
DISPLAY INVISIBLE (7125 4750);
FORCEPROP 2 LAST CDS_LIB mstr_misc
J 0
(7125 4750);
DISPLAY INVISIBLE (7125 4750);
FORCEADD DNS..2
(6800 4525);
PAINT RED (6800 4525);
FORCEPROP 1 LAST COMMENT_BODY TRUE
J 0
(6800 4525);
DISPLAY INVISIBLE (6800 4525);
FORCEPROP 2 LAST CDS_LIB mstr_misc
J 0
(6800 4525);
DISPLAY INVISIBLE (6800 4525);
FORCEADD DNS..2
(6425 4525);
PAINT RED (6425 4525);
FORCEPROP 1 LAST COMMENT_BODY TRUE
J 0
(6425 4525);
DISPLAY INVISIBLE (6425 4525);
FORCEPROP 2 LAST CDS_LIB mstr_misc
J 0
(6425 4525);
DISPLAY INVISIBLE (6425 4525);
FORCEADD DNS..2
(3725 4550);
PAINT RED (3725 4550);
FORCEPROP 1 LAST COMMENT_BODY TRUE
J 0
(3725 4550);
DISPLAY INVISIBLE (3725 4550);
FORCEPROP 2 LAST CDS_LIB mstr_misc
J 0
(3725 4550);
DISPLAY INVISIBLE (3725 4550);
FORCEADD DNS..2
(4100 4550);
PAINT RED (4100 4550);
FORCEPROP 1 LAST COMMENT_BODY TRUE
J 0
(4100 4550);
DISPLAY INVISIBLE (4100 4550);
FORCEPROP 2 LAST CDS_LIB mstr_misc
J 0
(4100 4550);
DISPLAY INVISIBLE (4100 4550);
FORCEADD DNS..2
(4450 4725);
PAINT RED (4450 4725);
FORCEPROP 1 LAST COMMENT_BODY TRUE
J 0
(4450 4725);
DISPLAY INVISIBLE (4450 4725);
FORCEPROP 2 LAST CDS_LIB mstr_misc
J 0
(4450 4725);
DISPLAY INVISIBLE (4450 4725);
FORCEADD DNS..2
(5550 3125);
PAINT RED (5550 3125);
FORCEPROP 2 LAST CDS_LIB mstr_misc
J 0
(5550 3125);
DISPLAY INVISIBLE (5550 3125);
FORCEPROP 1 LAST COMMENT_BODY TRUE
J 0
(5550 3125);
DISPLAY INVISIBLE (5550 3125);
FORCEADD DNS..2
(1375 50);
PAINT RED (1375 50);
FORCEPROP 1 LAST COMMENT_BODY TRUE
J 0
(1375 50);
DISPLAY INVISIBLE (1375 50);
FORCEPROP 2 LAST CDS_LIB mstr_misc
J 0
(1375 50);
DISPLAY INVISIBLE (1375 50);
FORCEADD DNS..2
(4425 1675);
PAINT RED (4425 1675);
FORCEPROP 1 LAST COMMENT_BODY TRUE
J 0
(4425 1675);
DISPLAY INVISIBLE (4425 1675);
FORCEPROP 2 LAST CDS_LIB mstr_misc
J 0
(4425 1675);
DISPLAY INVISIBLE (4425 1675);
FORCEADD DNS..2
(4450 1200);
PAINT RED (4450 1200);
FORCEPROP 2 LAST CDS_LIB mstr_misc
J 0
(4450 1200);
DISPLAY INVISIBLE (4450 1200);
FORCEPROP 1 LAST COMMENT_BODY TRUE
J 0
(4450 1200);
DISPLAY INVISIBLE (4450 1200);
FORCEADD DNS..2
(2925 3050);
PAINT RED (2925 3050);
FORCEPROP 1 LAST COMMENT_BODY TRUE
J 0
(2925 3050);
DISPLAY INVISIBLE (2925 3050);
FORCEPROP 2 LAST CDS_LIB mstr_misc
J 0
(2925 3050);
DISPLAY INVISIBLE (2925 3050);
FORCEADD DNS..2
(2225 3075);
PAINT RED (2225 3075);
FORCEPROP 1 LAST COMMENT_BODY TRUE
J 0
(2225 3075);
DISPLAY INVISIBLE (2225 3075);
FORCEPROP 2 LAST CDS_LIB mstr_misc
J 0
(2225 3075);
DISPLAY INVISIBLE (2225 3075);
FORCEADD DNS..2
(2225 3225);
PAINT RED (2225 3225);
FORCEPROP 2 LAST CDS_LIB mstr_misc
J 0
(2225 3225);
DISPLAY INVISIBLE (2225 3225);
FORCEPROP 1 LAST COMMENT_BODY TRUE
J 0
(2225 3225);
DISPLAY INVISIBLE (2225 3225);
FORCEADD DNS..2
(350 2275);
PAINT RED (350 2275);
FORCEPROP 1 LAST COMMENT_BODY TRUE
J 0
(350 2275);
DISPLAY INVISIBLE (350 2275);
FORCEPROP 2 LAST CDS_LIB mstr_misc
J 0
(350 2275);
DISPLAY INVISIBLE (350 2275);
FORCEADD DNS..2
(-350 2700);
PAINT RED (-350 2700);
FORCEPROP 2 LAST CDS_LIB mstr_misc
J 0
(-350 2700);
DISPLAY INVISIBLE (-350 2700);
FORCEPROP 1 LAST COMMENT_BODY TRUE
J 0
(-350 2700);
DISPLAY INVISIBLE (-350 2700);
FORCEADD DNS..2
(2250 4075);
PAINT RED (2250 4075);
FORCEPROP 2 LAST CDS_LIB mstr_misc
J 0
(2250 4075);
DISPLAY INVISIBLE (2250 4075);
FORCEPROP 1 LAST COMMENT_BODY TRUE
J 0
(2250 4075);
DISPLAY INVISIBLE (2250 4075);
FORCEADD DNS..2
(2250 4225);
PAINT RED (2250 4225);
FORCEPROP 1 LAST COMMENT_BODY TRUE
J 0
(2250 4225);
DISPLAY INVISIBLE (2250 4225);
FORCEPROP 2 LAST CDS_LIB mstr_misc
J 0
(2250 4225);
DISPLAY INVISIBLE (2250 4225);
FORCEADD DNS..2
(2950 4050);
PAINT RED (2950 4050);
FORCEPROP 2 LAST CDS_LIB mstr_misc
J 0
(2950 4050);
DISPLAY INVISIBLE (2950 4050);
FORCEPROP 1 LAST COMMENT_BODY TRUE
J 0
(2950 4050);
DISPLAY INVISIBLE (2950 4050);
FORCEADD DNS..2
(-175 1400);
PAINT RED (-175 1400);
FORCEPROP 1 LAST COMMENT_BODY TRUE
J 0
(-175 1400);
DISPLAY INVISIBLE (-175 1400);
FORCEPROP 2 LAST CDS_LIB mstr_misc
J 0
(-175 1400);
DISPLAY INVISIBLE (-175 1400);
FORCEADD DNS..2
(725 975);
PAINT RED (725 975);
FORCEPROP 2 LAST CDS_LIB mstr_misc
J 0
(725 975);
DISPLAY INVISIBLE (725 975);
FORCEPROP 1 LAST COMMENT_BODY TRUE
J 0
(725 975);
DISPLAY INVISIBLE (725 975);
FORCEADD DNS..2
(3600 500);
PAINT RED (3600 500);
FORCEPROP 1 LAST COMMENT_BODY TRUE
J 0
(3600 500);
DISPLAY INVISIBLE (3600 500);
FORCEPROP 2 LAST CDS_LIB mstr_misc
J 0
(3600 500);
PAINT MONO (3600 500);
DISPLAY INVISIBLE (3600 500);
FORCEADD DNS..2
(3350 500);
PAINT RED (3350 500);
FORCEPROP 2 LAST CDS_LIB mstr_misc
J 0
(3350 500);
PAINT MONO (3350 500);
DISPLAY INVISIBLE (3350 500);
FORCEPROP 1 LAST COMMENT_BODY TRUE
J 0
(3350 500);
DISPLAY INVISIBLE (3350 500);
FORCEADD DNS..2
(5500 4075);
PAINT RED (5500 4075);
FORCEPROP 2 LAST CDS_LIB mstr_misc
J 0
(5500 4075);
DISPLAY INVISIBLE (5500 4075);
FORCEPROP 1 LAST COMMENT_BODY TRUE
J 0
(5500 4075);
DISPLAY INVISIBLE (5500 4075);
FORCEADD CAD_NOTE..1
(4375 2700);
FORCEPROP 0 LAST S1 U193 & U269 CO-LAYOUT, U193 IS 2ND SOLUTION
J 0
(4225 2550);
DISPLAY 1.021277 (4225 2550);
PAINT SKYBLUE (4225 2550);
FORCEPROP 1 LAST COMMENT_BODY TRUE
J 0
(4400 2800);
DISPLAY 0.978723 (4400 2800);
DISPLAY INVISIBLE (4400 2800);
FORCEPROP 2 LAST CDS_LIB logical_power
J 0
(4375 2700);
DISPLAY INVISIBLE (4375 2700);
FORCEADD DNS..2
(-275 5175);
PAINT RED (-275 5175);
FORCEPROP 1 LAST COMMENT_BODY TRUE
J 0
(-275 5175);
DISPLAY INVISIBLE (-275 5175);
FORCEPROP 2 LAST CDS_LIB mstr_misc
J 0
(-275 5175);
DISPLAY INVISIBLE (-275 5175);
FORCEADD DNS..2
(-350 3850);
PAINT RED (-350 3850);
FORCEPROP 1 LAST COMMENT_BODY TRUE
J 0
(-350 3850);
DISPLAY INVISIBLE (-350 3850);
FORCEPROP 2 LAST CDS_LIB mstr_misc
J 0
(-350 3850);
DISPLAY INVISIBLE (-350 3850);
FORCEADD DNS..2
(375 3425);
PAINT RED (375 3425);
FORCEPROP 2 LAST CDS_LIB mstr_misc
J 0
(375 3425);
DISPLAY INVISIBLE (375 3425);
FORCEPROP 1 LAST COMMENT_BODY TRUE
J 0
(375 3425);
DISPLAY INVISIBLE (375 3425);
FORCEADD DNS..2
(450 4775);
PAINT RED (450 4775);
FORCEPROP 2 LAST CDS_LIB mstr_misc
J 0
(450 4775);
DISPLAY INVISIBLE (450 4775);
FORCEPROP 1 LAST COMMENT_BODY TRUE
J 0
(450 4775);
DISPLAY INVISIBLE (450 4775);
FORCEADD DNS..2
(2275 5050);
PAINT RED (2275 5050);
FORCEPROP 2 LAST CDS_LIB mstr_misc
J 0
(2275 5050);
DISPLAY INVISIBLE (2275 5050);
FORCEPROP 1 LAST COMMENT_BODY TRUE
J 0
(2275 5050);
DISPLAY INVISIBLE (2275 5050);
FORCEADD DNS..2
(2275 5200);
PAINT RED (2275 5200);
FORCEPROP 1 LAST COMMENT_BODY TRUE
J 0
(2275 5200);
DISPLAY INVISIBLE (2275 5200);
FORCEPROP 2 LAST CDS_LIB mstr_misc
J 0
(2275 5200);
DISPLAY INVISIBLE (2275 5200);
FORCEADD DNS..2
(2975 5025);
PAINT RED (2975 5025);
FORCEPROP 1 LAST COMMENT_BODY TRUE
J 0
(2975 5025);
DISPLAY INVISIBLE (2975 5025);
FORCEPROP 2 LAST CDS_LIB mstr_misc
J 0
(2975 5025);
DISPLAY INVISIBLE (2975 5025);
FORCEADD DNS..2
(500 500);
PAINT RED (500 500);
FORCEPROP 1 LAST COMMENT_BODY TRUE
J 0
(500 500);
DISPLAY INVISIBLE (500 500);
FORCEPROP 2 LAST CDS_LIB mstr_misc
J 0
(500 500);
DISPLAY INVISIBLE (500 500);
WIRE 16 -1 (-1000 5525)(-1000 5625);
WIRE 16 -1 (3250 1900)(3250 2100);
WIRE 16 -1 (3250 1900)(3450 1900);
WIRE 16 -1 (3350 875)(3350 800);
WIRE 16 -1 (7525 4725)(7525 4900);
WIRE 16 -1 (7200 4725)(7525 4725);
WIRE 16 -1 (-1000 3050)(-1000 3150);
WIRE 16 -1 (-1025 1750)(-1025 1850);
WIRE 16 -1 (-1000 4300)(-1000 4200);
WIRE 16 -1 (-475 50)(-475 -25);
WIRE 16 -1 (1025 -25)(1025 -125);
WIRE 16 -1 (1375 -25)(1375 -150);
WIRE 16 -1 (2900 2450)(2900 2425);
WIRE 16 -1 (2925 2975)(2925 2925);
WIRE 16 -1 (325 2175)(325 2050);
WIRE 16 -1 (-25 2175)(-25 2050);
WIRE 16 -1 (2950 3975)(2950 3925);
WIRE 16 -1 (2925 3450)(2925 3425);
WIRE 16 -1 (350 875)(350 750);
WIRE 16 -1 (700 875)(700 750);
WIRE 16 -1 (-1025 1100)(-1025 950);
WIRE 16 -1 (-1000 2300)(-1000 2150);
WIRE 16 -1 (-1000 3525)(-1000 3425);
WIRE 16 -1 (-1000 4600)(-1000 4800);
WIRE 16 -1 (4425 1100)(4425 925);
WIRE 16 -1 (3725 1425)(4050 1425);
WIRE 16 -1 (3725 1600)(3725 1425);
WIRE 16 -1 (6850 875)(6850 725);
WIRE 16 -1 (6675 875)(6850 875);
WIRE 16 -1 (3350 -175)(3350 -250);
WIRE 16 -1 (3600 -175)(3600 -250);
WIRE 16 -1 (6775 4425)(6775 4400);
WIRE 16 -1 (6400 4400)(6400 4425);
WIRE 16 -1 (6000 3400)(6000 4350);
WIRE 16 -1 (4975 4150)(4975 3450);
WIRE 16 -1 (4975 4250)(4975 4150);
WIRE 16 -1 (5075 4150)(4975 4150);
WIRE 16 -1 (350 3325)(350 3200);
WIRE 16 -1 (0 3325)(0 3200);
WIRE 16 -1 (425 4675)(425 4550);
WIRE 16 -1 (75 4675)(75 4550);
WIRE 16 -1 (4075 4450)(4075 4400);
WIRE 16 -1 (3700 4400)(3700 4450);
WIRE 16 -1 (2950 4425)(2950 4400);
WIRE 16 -1 (2975 4950)(2975 4900);
WIRE 16 -1 (3350 625)(3350 800);
WIRE 16 -1 (3600 800)(3350 800);
WIRE 16 -1 (3600 625)(3600 800);
WIRE 16 -1 (4050 1600)(4050 1425);
WIRE 16 -1 (5650 1725)(5875 1725);
WIRE 16 -1 (5650 1900)(5650 1725);
WIRE 16 -1 (4425 1900)(4425 1800);
WIRE 16 -1 (4425 1900)(5650 1900);
WIRE 16 -1 (4050 1900)(4050 1800);
WIRE 16 -1 (4050 1900)(4425 1900);
WIRE 16 -1 (3725 1900)(3725 1800);
WIRE 16 -1 (3725 1900)(4050 1900);
WIRE 16 -1 (3650 1900)(3725 1900);
FORCEPROP 2 LAST SIG_NAME P3V3_ADC128_VCC
J 0
(3740 1910);
DISPLAY 0.510638 (3740 1910);
PAINT WHITE (3740 1910);
WIRE 16 2175 (-475 1125)(125 1125);
WIRE 16 2175 (125 1475)(125 1125);
WIRE 16 2175 (-475 1475)(-475 1125);
WIRE 16 2175 (-475 1475)(125 1475);
FORCEPROP 0 LAST M1 CO-LAYOUT
J 0
(-375 1500);
DISPLAY 1.021277 (-375 1500);
WIRE 16 -1 (5875 1325)(5200 1325);
FORCEPROP 0 LAST CDS_PHYS_NET_NAME SMB_SEN_3V3AUX_SCL
J 0
(5565 1373);
PAINT MONO (5565 1373);
DISPLAY INVISIBLE (5565 1373);
FORCEPROP 2 LAST SIG_NAME ADC128_A0
J 0
(5215 1335);
DISPLAY 0.510638 (5215 1335);
PAINT WHITE (5215 1335);
WIRE 16 -1 (5875 1575)(5200 1575);
FORCEPROP 0 LAST CDS_PHYS_NET_NAME SMB_TMP75_21_3V3AUX_SDA_R
J 0
(5565 1623);
PAINT MONO (5565 1623);
DISPLAY INVISIBLE (5565 1623);
FORCEPROP 2 LAST SIG_NAME SMB_SEN_TIC_3V3AUX_SDA
J 0
(5215 1585);
DISPLAY 0.510638 (5215 1585);
PAINT WHITE (5215 1585);
WIRE 16 -1 (-1100 750)(-475 750);
FORCEPROP 2 LAST SIG_NAME P3V3_PDB_AUX_ADC
J 0
(-1060 760);
DISPLAY 0.510638 (-1060 760);
PAINT WHITE (-1060 760);
WIRE 16 -1 (-475 750)(-475 625);
WIRE 16 2175 (2050 4000)(2550 4000);
WIRE 16 2175 (2550 4350)(2550 4000);
WIRE 16 2175 (2050 4350)(2050 4000);
WIRE 16 2175 (2050 4350)(2550 4350);
FORCEPROP 0 LAST M1 CO-LAYOUT
J 0
(2100 4350);
DISPLAY 1.021277 (2100 4350);
WIRE 16 -1 (1375 4550)(2150 4550);
FORCEPROP 0 LAST CDS_PHYS_NET_NAME P12V_OCP_SFF_ISENSE_MPS_TIC
J 0
(1915 4598);
PAINT MONO (1915 4598);
DISPLAY INVISIBLE (1915 4598);
FORCEPROP 2 LAST SIG_NAME P12V_OCP_SFF_ISENSE_MPS_TIC
J 0
(1415 4560);
DISPLAY 0.510638 (1415 4560);
PAINT WHITE (1415 4560);
WIRE 16 -1 (1375 4700)(2150 4700);
FORCEPROP 0 LAST CDS_PHYS_NET_NAME P12V_OCP_SFF_ISENSE_MAM_TIC
J 0
(2015 4748);
PAINT MONO (2015 4748);
DISPLAY INVISIBLE (2015 4748);
FORCEPROP 2 LAST SIG_NAME P12V_OCP_SFF_ISENSE_MAM_TIC
J 0
(1415 4710);
DISPLAY 0.510638 (1415 4710);
PAINT WHITE (1415 4710);
WIRE 16 -1 (425 4875)(425 5175);
WIRE 16 -1 (450 5175)(425 5175);
WIRE 16 -1 (-200 5175)(425 5175);
FORCEPROP 0 LAST CDS_PHYS_NET_NAME P3V3_AUX_SENSE
J 0
(365 5223);
PAINT MONO (365 5223);
DISPLAY INVISIBLE (365 5223);
FORCEPROP 2 LAST SIG_NAME P3V3_AUX_ADC_MAM
J 0
(40 5185);
DISPLAY 0.510638 (40 5185);
PAINT WHITE (40 5185);
WIRE 16 2175 (-575 5250)(25 5250);
FORCEPROP 0 LAST M1 CO-LAYOUT
J 0
(-475 5275);
DISPLAY 1.021277 (-475 5275);
WIRE 16 2175 (25 5250)(25 4900);
WIRE 16 2175 (-575 5250)(-575 4900);
WIRE 16 2175 (-575 4900)(25 4900);
WIRE 16 -1 (1350 4225)(2125 4225);
FORCEPROP 0 LAST CDS_PHYS_NET_NAME P12V_OCP_V3_2_ISENSE_MAM_MAM
J 0
(1990 4273);
PAINT MONO (1990 4273);
DISPLAY INVISIBLE (1990 4273);
FORCEPROP 2 LAST SIG_NAME P12V_OCP_V3_2_ISENSE_MAM_MAM
J 0
(1340 4235);
DISPLAY 0.510638 (1340 4235);
PAINT WHITE (1340 4235);
WIRE 16 -1 (2950 4625)(2950 4700);
WIRE 16 -1 (2950 4700)(3175 4700);
WIRE 16 -1 (2350 4700)(2725 4700);
FORCEPROP 2 LAST SIG_NAME P12V_OCP_SFF_ISENSE_TIC
J 0
(2615 4710);
DISPLAY 0.510638 (2615 4710);
PAINT WHITE (2615 4710);
WIRE 16 -1 (2725 4700)(2950 4700);
FORCEPROP 0 LAST CDS_PHYS_NET_NAME P12V_OCP_SFF_ISENSE_TIC
J 0
(2915 4748);
PAINT MONO (2915 4748);
DISPLAY INVISIBLE (2915 4748);
WIRE 16 -1 (2725 4550)(2725 4700);
WIRE 16 -1 (2350 4550)(2725 4550);
WIRE 16 -1 (2950 4175)(2950 4225);
WIRE 16 -1 (3150 4225)(2950 4225);
WIRE 16 -1 (2325 4225)(2700 4225);
FORCEPROP 2 LAST SIG_NAME P12V_OCP_V3_2_ISENSE_MAM
J 0
(2590 4235);
DISPLAY 0.510638 (2590 4235);
PAINT WHITE (2590 4235);
WIRE 16 -1 (2700 4225)(2950 4225);
FORCEPROP 0 LAST CDS_PHYS_NET_NAME P12V_OCP_V3_2_ISENSE_MAM
J 0
(2890 4273);
PAINT MONO (2890 4273);
DISPLAY INVISIBLE (2890 4273);
WIRE 16 -1 (2700 4075)(2700 4225);
WIRE 16 -1 (2325 4075)(2700 4075);
WIRE 16 -1 (2925 3650)(2925 3725);
WIRE 16 -1 (2925 3725)(3150 3725);
WIRE 16 -1 (2325 3725)(2700 3725);
FORCEPROP 2 LAST SIG_NAME P12V_OCP_V3_2_ISENSE_TIC
J 0
(2590 3735);
DISPLAY 0.510638 (2590 3735);
PAINT WHITE (2590 3735);
WIRE 16 -1 (2700 3725)(2925 3725);
FORCEPROP 0 LAST CDS_PHYS_NET_NAME P12V_OCP_V3_2_ISENSE_TIC
J 0
(2890 3773);
PAINT MONO (2890 3773);
DISPLAY INVISIBLE (2890 3773);
WIRE 16 -1 (2700 3575)(2700 3725);
WIRE 16 -1 (2325 3575)(2700 3575);
WIRE 16 -1 (2300 3075)(2675 3075);
WIRE 16 -1 (2300 3225)(2675 3225);
FORCEPROP 2 LAST SIG_NAME P12V_E1S_0_ISENSE_MAM
J 0
(2565 3235);
DISPLAY 0.510638 (2565 3235);
PAINT WHITE (2565 3235);
WIRE 16 -1 (2675 3075)(2675 3225);
WIRE 16 -1 (2675 3225)(2925 3225);
FORCEPROP 0 LAST CDS_PHYS_NET_NAME P12V_OCP_V3_2_ISENSE_MAM
J 0
(2865 3273);
PAINT MONO (2865 3273);
DISPLAY INVISIBLE (2865 3273);
WIRE 16 -1 (3125 3225)(2925 3225);
WIRE 16 -1 (2925 3175)(2925 3225);
WIRE 16 2175 (2000 3350)(2525 3350);
FORCEPROP 0 LAST M1 CO-LAYOUT
J 0
(2050 3350);
DISPLAY 1.021277 (2050 3350);
WIRE 16 2175 (2525 3350)(2525 3000);
WIRE 16 2175 (2000 3350)(2000 3000);
WIRE 16 2175 (2000 3000)(2525 3000);
WIRE 16 -1 (1325 3075)(2100 3075);
FORCEPROP 0 LAST CDS_PHYS_NET_NAME P12V_OCP_V3_2_ISENSE_MPS_MAM
J 0
(1865 3123);
PAINT MONO (1865 3123);
DISPLAY INVISIBLE (1865 3123);
FORCEPROP 2 LAST SIG_NAME P12V_E1S_0_ISENSE_MPS_MAM
J 0
(1315 3085);
DISPLAY 0.510638 (1315 3085);
PAINT WHITE (1315 3085);
WIRE 16 -1 (1350 4075)(2125 4075);
FORCEPROP 0 LAST CDS_PHYS_NET_NAME P12V_OCP_V3_2_ISENSE_MPS_MAM
J 0
(1890 4123);
PAINT MONO (1890 4123);
DISPLAY INVISIBLE (1890 4123);
FORCEPROP 2 LAST SIG_NAME P12V_OCP_V3_2_ISENSE_MPS_MAM
J 0
(1340 4085);
DISPLAY 0.510638 (1340 4085);
PAINT WHITE (1340 4085);
WIRE 16 -1 (5075 4050)(4275 4050);
FORCEPROP 0 LAST CDS_PHYS_NET_NAME SMB_SEN_3V3AUX_SCL
J 0
(4765 4098);
PAINT MONO (4765 4098);
DISPLAY INVISIBLE (4765 4098);
FORCEPROP 2 LAST SIG_NAME P12V_AUX_ADC_MAM
J 0
(4365 4060);
DISPLAY 0.510638 (4365 4060);
PAINT WHITE (4365 4060);
WIRE 16 2175 (2075 2475)(2600 2475);
WIRE 16 2175 (2600 2825)(2600 2475);
WIRE 16 2175 (2075 2825)(2075 2475);
WIRE 16 2175 (2075 2825)(2600 2825);
FORCEPROP 0 LAST M1 CO-LAYOUT
J 0
(2125 2825);
DISPLAY 1.021277 (2125 2825);
WIRE 16 -1 (1325 3225)(2100 3225);
FORCEPROP 0 LAST CDS_PHYS_NET_NAME P12V_OCP_V3_2_ISENSE_MAM_MAM
J 0
(1965 3273);
PAINT MONO (1965 3273);
DISPLAY INVISIBLE (1965 3273);
FORCEPROP 2 LAST SIG_NAME P12V_E1S_0_ISENSE_MAM_MAM
J 0
(1315 3235);
DISPLAY 0.510638 (1315 3235);
PAINT WHITE (1315 3235);
WIRE 16 2175 (2050 3500)(2550 3500);
WIRE 16 2175 (2550 3850)(2550 3500);
WIRE 16 2175 (2050 3850)(2050 3500);
WIRE 16 2175 (2050 3850)(2550 3850);
FORCEPROP 0 LAST M1 CO-LAYOUT
J 0
(2100 3850);
DISPLAY 1.021277 (2100 3850);
WIRE 16 2175 (2075 4825)(2575 4825);
FORCEPROP 0 LAST M1 CO-LAYOUT
J 0
(2125 4825);
DISPLAY 1.021277 (2125 4825);
WIRE 16 2175 (2575 4825)(2575 4475);
WIRE 16 2175 (2075 4825)(2075 4475);
WIRE 16 2175 (2075 4475)(2575 4475);
WIRE 16 -1 (5075 3950)(4275 3950);
FORCEPROP 0 LAST CDS_PHYS_NET_NAME SMB_SEN_3V3AUX_SCL
J 0
(4765 3998);
PAINT MONO (4765 3998);
DISPLAY INVISIBLE (4765 3998);
FORCEPROP 2 LAST SIG_NAME P12V_OCP_SFF_ISENSE_MAM
J 0
(4365 3960);
DISPLAY 0.510638 (4365 3960);
PAINT WHITE (4365 3960);
WIRE 16 -1 (5075 4250)(4975 4250);
WIRE 16 -1 (4975 4350)(4975 4250);
WIRE 16 -1 (5075 4350)(4975 4350);
WIRE 16 -1 (6525 3150)(5625 3150);
FORCEPROP 0 LAST CDS_PHYS_NET_NAME SMB_TMP75_21_3V3AUX_SDA_R
J 0
(6065 3198);
PAINT MONO (6065 3198);
DISPLAY INVISIBLE (6065 3198);
FORCEPROP 2 LAST SIG_NAME SMB_SEN_MAM_3V3AUX_SDA
J 0
(5940 3160);
DISPLAY 0.510638 (5940 3160);
PAINT WHITE (5940 3160);
WIRE 16 -1 (4425 1475)(4425 1300);
WIRE 16 -1 (4425 1600)(4425 1475);
WIRE 16 -1 (5875 1475)(4425 1475);
FORCEPROP 0 LAST CDS_PHYS_NET_NAME SMB_TMP75_21_3V3AUX_SDA_R
J 0
(5565 1523);
PAINT MONO (5565 1523);
DISPLAY INVISIBLE (5565 1523);
FORCEPROP 2 LAST SIG_NAME ADC128_VREF
J 0
(5215 1485);
DISPLAY 0.510638 (5215 1485);
PAINT WHITE (5215 1485);
WIRE 16 -1 (5875 1025)(5200 1025);
FORCEPROP 0 LAST CDS_PHYS_NET_NAME P5V_ADC_TIC
J 0
(5565 1073);
PAINT MONO (5565 1073);
DISPLAY INVISIBLE (5565 1073);
FORCEPROP 2 LAST SIG_NAME P5V_ADC_TIC
J 0
(5215 1035);
DISPLAY 0.510638 (5215 1035);
PAINT WHITE (5215 1035);
WIRE 16 -1 (5875 1075)(5200 1075);
FORCEPROP 0 LAST CDS_PHYS_NET_NAME P3V3_ADC_TIC
J 0
(5565 1123);
PAINT MONO (5565 1123);
DISPLAY INVISIBLE (5565 1123);
FORCEPROP 2 LAST SIG_NAME P3V3_ADC_TIC
J 0
(5215 1085);
DISPLAY 0.510638 (5215 1085);
PAINT WHITE (5215 1085);
WIRE 16 -1 (5875 1225)(5200 1225);
FORCEPROP 0 LAST CDS_PHYS_NET_NAME P3V3_PDB_AUX_ADC_TIC
J 0
(5565 1273);
PAINT MONO (5565 1273);
DISPLAY INVISIBLE (5565 1273);
FORCEPROP 2 LAST SIG_NAME P12V_E1S_0_ISENSE_TIC
J 0
(5215 1235);
DISPLAY 0.510638 (5215 1235);
PAINT WHITE (5215 1235);
WIRE 16 -1 (1450 5475)(1900 5475);
WIRE 16 -1 (1450 5600)(1450 5475);
WIRE 16 -1 (1450 5725)(1450 5600);
WIRE 16 -1 (1900 5725)(1450 5725);
WIRE 16 -1 (1450 5600)(1900 5600);
WIRE 16 -1 (1900 5475)(1900 5600);
WIRE 16 -1 (1900 5600)(1900 5725);
WIRE 16 -1 (1900 5475)(2325 5475);
WIRE 16 -1 (2325 5475)(2750 5475);
WIRE 16 -1 (1900 5600)(2325 5600);
WIRE 16 -1 (2325 5600)(2325 5475);
WIRE 16 -1 (2325 5725)(1900 5725);
WIRE 16 -1 (2325 5725)(2325 5600);
WIRE 16 -1 (2750 5725)(2325 5725);
WIRE 16 -1 (2750 5600)(2325 5600);
WIRE 16 -1 (2750 5475)(2750 5600);
WIRE 16 -1 (2750 5600)(2750 5725);
WIRE 16 -1 (2750 5475)(3125 5475);
WIRE 16 -1 (3125 5475)(3575 5475);
WIRE 16 -1 (3125 5600)(2750 5600);
WIRE 16 -1 (3125 5600)(3125 5475);
WIRE 16 -1 (2750 5725)(3125 5725);
WIRE 16 -1 (3125 5725)(3125 5600);
WIRE 16 -1 (3575 5725)(3125 5725);
WIRE 16 -1 (3125 5600)(3575 5600);
WIRE 16 -1 (3575 5475)(3575 5600);
WIRE 16 -1 (3575 5600)(3575 5725);
WIRE 16 -1 (5075 3850)(4275 3850);
FORCEPROP 0 LAST CDS_PHYS_NET_NAME P12V_AUX_ADC_MAM
J 0
(4765 3898);
PAINT MONO (4765 3898);
DISPLAY INVISIBLE (4765 3898);
FORCEPROP 2 LAST SIG_NAME P12V_OCP_V3_2_ISENSE_MAM
J 0
(4365 3860);
DISPLAY 0.510638 (4365 3860);
PAINT WHITE (4365 3860);
WIRE 16 -1 (5075 3750)(4275 3750);
FORCEPROP 0 LAST CDS_PHYS_NET_NAME P5V_ADC_MAM
J 0
(4765 3798);
PAINT MONO (4765 3798);
DISPLAY INVISIBLE (4765 3798);
FORCEPROP 2 LAST SIG_NAME P5V_ADC_MAM
J 0
(4365 3760);
DISPLAY 0.510638 (4365 3760);
PAINT WHITE (4365 3760);
WIRE 16 -1 (4575 3100)(5425 3100);
FORCEPROP 0 LAST CDS_PHYS_NET_NAME SMB_TEMP_3V3AUX_SCL
J 0
(4615 3148);
PAINT MONO (4615 3148);
DISPLAY INVISIBLE (4615 3148);
FORCEPROP 2 LAST SIG_NAME SMB_VR_3V3AUX_SCL_R1
J 0
(4665 3110);
DISPLAY 0.510638 (4665 3110);
PAINT WHITE (4665 3110);
WIRE 16 2175 (225 250)(800 250);
WIRE 16 2175 (800 600)(800 250);
WIRE 16 2175 (225 600)(225 250);
WIRE 16 2175 (225 600)(800 600);
FORCEPROP 0 LAST M1 CO-LAYOUT
J 0
(325 625);
DISPLAY 1.021277 (325 625);
WIRE 16 -1 (350 1075)(350 1250);
WIRE 16 -1 (350 1250)(875 1250);
FORCEPROP 0 LAST CDS_PHYS_NET_NAME P3V3_AUX_SENSE
J 0
(740 1298);
PAINT MONO (740 1298);
DISPLAY INVISIBLE (740 1298);
WIRE 16 -1 (-100 1250)(350 1250);
FORCEPROP 2 LAST SIG_NAME P12V_AUX_ADC_TIC
J 0
(140 1260);
DISPLAY 0.510638 (140 1260);
PAINT WHITE (140 1260);
WIRE 16 -1 (700 1075)(700 1400);
WIRE 16 -1 (700 1400)(875 1400);
WIRE 16 -1 (-100 1400)(700 1400);
FORCEPROP 0 LAST CDS_PHYS_NET_NAME P3V3_AUX_SENSE
J 0
(465 1448);
PAINT MONO (465 1448);
DISPLAY INVISIBLE (465 1448);
FORCEPROP 2 LAST SIG_NAME P12V_AUX_ADC_MAM
J 0
(140 1410);
DISPLAY 0.510638 (140 1410);
PAINT WHITE (140 1410);
WIRE 16 -1 (2900 2650)(2900 2725);
WIRE 16 -1 (2900 2725)(3125 2725);
WIRE 16 -1 (2300 2725)(2675 2725);
FORCEPROP 2 LAST SIG_NAME P12V_E1S_0_ISENSE_TIC
J 0
(2565 2735);
DISPLAY 0.510638 (2565 2735);
PAINT WHITE (2565 2735);
WIRE 16 -1 (2675 2725)(2900 2725);
FORCEPROP 0 LAST CDS_PHYS_NET_NAME P12V_OCP_V3_2_ISENSE_TIC
J 0
(2865 2773);
PAINT MONO (2865 2773);
DISPLAY INVISIBLE (2865 2773);
WIRE 16 -1 (2675 2575)(2675 2725);
WIRE 16 -1 (2300 2575)(2675 2575);
WIRE 16 -1 (1325 2575)(2100 2575);
FORCEPROP 0 LAST CDS_PHYS_NET_NAME P12V_OCP_V3_2_ISENSE_MPS_MAM
J 0
(1865 2623);
PAINT MONO (1865 2623);
DISPLAY INVISIBLE (1865 2623);
FORCEPROP 2 LAST SIG_NAME P12V_E1S_0_ISENSE_MPS_TIC
J 0
(1365 2585);
DISPLAY 0.510638 (1365 2585);
PAINT WHITE (1365 2585);
WIRE 16 -1 (1325 2725)(2100 2725);
FORCEPROP 0 LAST CDS_PHYS_NET_NAME P12V_OCP_V3_2_ISENSE_MAM_TIC
J 0
(1965 2773);
PAINT MONO (1965 2773);
DISPLAY INVISIBLE (1965 2773);
FORCEPROP 2 LAST SIG_NAME P12V_E1S_0_ISENSE_MAM_TIC
J 0
(1365 2735);
DISPLAY 0.510638 (1365 2735);
PAINT WHITE (1365 2735);
WIRE 16 -1 (1350 3575)(2125 3575);
FORCEPROP 0 LAST CDS_PHYS_NET_NAME P12V_OCP_V3_2_ISENSE_MPS_MAM
J 0
(1890 3623);
PAINT MONO (1890 3623);
DISPLAY INVISIBLE (1890 3623);
FORCEPROP 2 LAST SIG_NAME P12V_OCP_V3_2_ISENSE_MPS_TIC
J 0
(1365 3585);
DISPLAY 0.510638 (1365 3585);
PAINT WHITE (1365 3585);
WIRE 16 -1 (575 500)(1375 500);
FORCEPROP 0 LAST CDS_PHYS_NET_NAME P3V3_AUX_SENSE
J 0
(1140 548);
PAINT MONO (1140 548);
DISPLAY INVISIBLE (1140 548);
FORCEPROP 2 LAST SIG_NAME P3V3_PDB_AUX_ADC_MAM
J 0
(815 510);
DISPLAY 0.510638 (815 510);
PAINT WHITE (815 510);
WIRE 16 -1 (1375 500)(1550 500);
WIRE 16 -1 (1375 175)(1375 500);
WIRE 16 -1 (1025 175)(1025 350);
WIRE 16 -1 (1025 350)(1550 350);
FORCEPROP 0 LAST CDS_PHYS_NET_NAME P3V3_AUX_SENSE
J 0
(1415 398);
PAINT MONO (1415 398);
DISPLAY INVISIBLE (1415 398);
WIRE 16 -1 (575 350)(1025 350);
FORCEPROP 2 LAST SIG_NAME P3V3_PDB_AUX_ADC_TIC
J 0
(815 360);
DISPLAY 0.510638 (815 360);
PAINT WHITE (815 360);
WIRE 16 2175 (-600 -125)(-100 -125);
WIRE 16 2175 (-100 700)(-100 -125);
WIRE 16 2175 (-600 700)(-600 -125);
WIRE 16 2175 (-600 700)(-100 700);
WIRE 16 -1 (-475 325)(-475 250);
WIRE 16 -1 (-475 425)(-475 325);
WIRE 16 -1 (-475 325)(75 325);
FORCEPROP 2 LAST SIG_NAME P1V581_PDB_ADC
J 0
(-260 335);
DISPLAY 0.510638 (-260 335);
PAINT WHITE (-260 335);
WIRE 16 -1 (75 500)(75 325);
WIRE 16 -1 (75 500)(250 500);
FORCEPROP 0 LAST CDS_PHYS_NET_NAME SMB_SEN_3V3AUX_SCL
J 0
(90 548);
PAINT MONO (90 548);
DISPLAY INVISIBLE (90 548);
WIRE 16 -1 (250 500)(375 500);
WIRE 16 -1 (250 350)(250 500);
WIRE 16 -1 (375 350)(250 350);
WIRE 16 -1 (-1025 1300)(-1025 1400);
WIRE 16 -1 (-1025 1550)(-1025 1400);
WIRE 16 -1 (-1025 1400)(-600 1400);
FORCEPROP 2 LAST SIG_NAME P12V_AUX_ADC
J 0
(-960 1410);
DISPLAY 0.510638 (-960 1410);
PAINT WHITE (-960 1410);
WIRE 16 -1 (-600 1400)(-300 1400);
FORCEPROP 0 LAST CDS_PHYS_NET_NAME P5V_SENSE
J 0
(-485 1448);
PAINT MONO (-485 1448);
DISPLAY INVISIBLE (-485 1448);
WIRE 16 -1 (-600 1250)(-600 1400);
WIRE 16 -1 (-300 1250)(-600 1250);
WIRE 16 2175 (-650 3575)(-50 3575);
WIRE 16 2175 (-50 3925)(-50 3575);
WIRE 16 2175 (-650 3925)(-650 3575);
WIRE 16 2175 (-650 3925)(-50 3925);
FORCEPROP 0 LAST M1 CO-LAYOUT
J 0
(-550 3950);
DISPLAY 1.021277 (-550 3950);
WIRE 16 -1 (-275 3850)(350 3850);
FORCEPROP 0 LAST CDS_PHYS_NET_NAME P3V3_AUX_SENSE
J 0
(290 3898);
PAINT MONO (290 3898);
DISPLAY INVISIBLE (290 3898);
FORCEPROP 2 LAST SIG_NAME P3V3_ADC_MAM
J 0
(-35 3860);
DISPLAY 0.510638 (-35 3860);
PAINT WHITE (-35 3860);
WIRE 16 -1 (400 3850)(350 3850);
WIRE 16 -1 (350 3525)(350 3850);
WIRE 16 -1 (-525 5025)(-400 5025);
WIRE 16 -1 (-525 5175)(-525 5025);
WIRE 16 -1 (-525 5175)(-400 5175);
WIRE 16 -1 (-1000 5325)(-1000 5175);
WIRE 16 -1 (-525 5175)(-1000 5175);
FORCEPROP 0 LAST CDS_PHYS_NET_NAME P3V3_AUX_SENSE
J 0
(-535 5223);
PAINT MONO (-535 5223);
DISPLAY INVISIBLE (-535 5223);
FORCEPROP 2 LAST SIG_NAME P3V3_AUX_ADC
J 0
(-885 5185);
DISPLAY 0.510638 (-885 5185);
PAINT WHITE (-885 5185);
WIRE 16 -1 (-1000 5000)(-1000 5175);
WIRE 16 -1 (400 3700)(0 3700);
FORCEPROP 0 LAST CDS_PHYS_NET_NAME P3V3_AUX_SENSE
J 0
(265 3748);
PAINT MONO (265 3748);
DISPLAY INVISIBLE (265 3748);
WIRE 16 -1 (-275 3700)(0 3700);
FORCEPROP 2 LAST SIG_NAME P3V3_ADC_TIC
J 0
(-35 3710);
DISPLAY 0.510638 (-35 3710);
PAINT WHITE (-35 3710);
WIRE 16 -1 (0 3525)(0 3700);
WIRE 16 -1 (1350 3725)(2125 3725);
FORCEPROP 0 LAST CDS_PHYS_NET_NAME P12V_OCP_V3_2_ISENSE_MAM_TIC
J 0
(1990 3773);
PAINT MONO (1990 3773);
DISPLAY INVISIBLE (1990 3773);
FORCEPROP 2 LAST SIG_NAME P12V_OCP_V3_2_ISENSE_MAM_TIC
J 0
(1365 3735);
DISPLAY 0.510638 (1365 3735);
PAINT WHITE (1365 3735);
WIRE 16 2175 (2100 4975)(2575 4975);
WIRE 16 2175 (2575 5325)(2575 4975);
WIRE 16 2175 (2100 5325)(2100 4975);
WIRE 16 2175 (2100 5325)(2575 5325);
FORCEPROP 0 LAST M1 CO-LAYOUT
J 0
(2150 5325);
DISPLAY 1.021277 (2150 5325);
WIRE 16 -1 (2975 5150)(2975 5200);
WIRE 16 -1 (3175 5200)(2975 5200);
WIRE 16 -1 (2350 5200)(2725 5200);
FORCEPROP 2 LAST SIG_NAME P12V_OCP_SFF_ISENSE_MAM
J 0
(2615 5210);
DISPLAY 0.510638 (2615 5210);
PAINT WHITE (2615 5210);
WIRE 16 -1 (2725 5200)(2975 5200);
FORCEPROP 0 LAST CDS_PHYS_NET_NAME P12V_OCP_SFF_ISENSE_MAM
J 0
(2915 5248);
PAINT MONO (2915 5248);
DISPLAY INVISIBLE (2915 5248);
WIRE 16 -1 (2725 5050)(2725 5200);
WIRE 16 -1 (2350 5050)(2725 5050);
WIRE 16 -1 (-475 2550)(-600 2550);
WIRE 16 -1 (-600 2700)(-600 2550);
WIRE 16 -1 (-600 2700)(-475 2700);
WIRE 16 -1 (-1000 2700)(-1000 2500);
WIRE 16 -1 (-1000 2850)(-1000 2700);
WIRE 16 -1 (-1000 2700)(-600 2700);
FORCEPROP 0 LAST CDS_PHYS_NET_NAME P3V3_AUX_SENSE
J 0
(-610 2748);
PAINT MONO (-610 2748);
DISPLAY INVISIBLE (-610 2748);
FORCEPROP 2 LAST SIG_NAME P5V_ADC
J 0
(-810 2710);
DISPLAY 0.510638 (-810 2710);
PAINT WHITE (-810 2710);
WIRE 16 2175 (-550 2775)(-50 2775);
FORCEPROP 0 LAST M1 CO-LAYOUT
J 0
(-450 2800);
DISPLAY 1.021277 (-450 2800);
WIRE 16 2175 (-50 2775)(-50 2425);
WIRE 16 2175 (-550 2775)(-550 2425);
WIRE 16 2175 (-550 2425)(-50 2425);
WIRE 16 -1 (-25 2375)(-25 2550);
WIRE 16 -1 (400 2550)(-25 2550);
FORCEPROP 0 LAST CDS_PHYS_NET_NAME P3V3_AUX_SENSE
J 0
(265 2598);
PAINT MONO (265 2598);
DISPLAY INVISIBLE (265 2598);
WIRE 16 -1 (-275 2550)(-25 2550);
FORCEPROP 2 LAST SIG_NAME P5V_ADC_TIC
J 0
(-35 2560);
DISPLAY 0.510638 (-35 2560);
PAINT WHITE (-35 2560);
WIRE 16 -1 (325 2375)(325 2700);
WIRE 16 -1 (400 2700)(325 2700);
WIRE 16 -1 (-275 2700)(325 2700);
FORCEPROP 0 LAST CDS_PHYS_NET_NAME P3V3_AUX_SENSE
J 0
(290 2748);
PAINT MONO (290 2748);
DISPLAY INVISIBLE (290 2748);
FORCEPROP 2 LAST SIG_NAME P5V_ADC_MAM
J 0
(-35 2710);
DISPLAY 0.510638 (-35 2710);
PAINT WHITE (-35 2710);
WIRE 16 -1 (75 4875)(75 5025);
WIRE 16 -1 (450 5025)(75 5025);
FORCEPROP 0 LAST CDS_PHYS_NET_NAME P3V3_AUX_SENSE
J 0
(315 5073);
PAINT MONO (315 5073);
DISPLAY INVISIBLE (315 5073);
WIRE 16 -1 (-200 5025)(75 5025);
FORCEPROP 2 LAST SIG_NAME P3V3_AUX_ADC_TIC
J 0
(40 5035);
DISPLAY 0.510638 (40 5035);
PAINT WHITE (40 5035);
WIRE 16 -1 (5875 1175)(5200 1175);
FORCEPROP 0 LAST CDS_PHYS_NET_NAME P3V3_PDB_AUX_ADC_TIC
J 0
(5565 1223);
PAINT MONO (5565 1223);
DISPLAY INVISIBLE (5565 1223);
FORCEPROP 2 LAST SIG_NAME P3V3_PDB_AUX_ADC_TIC
J 0
(5215 1185);
DISPLAY 0.510638 (5215 1185);
PAINT WHITE (5215 1185);
WIRE 16 -1 (5400 200)(6250 200);
FORCEPROP 0 LAST CDS_PHYS_NET_NAME SMB_TEMP_3V3AUX_SCL
J 0
(5440 248);
PAINT MONO (5440 248);
DISPLAY INVISIBLE (5440 248);
FORCEPROP 2 LAST SIG_NAME SMB_VR_3V3AUX_SCL_R1
J 0
(5490 210);
DISPLAY 0.510638 (5490 210);
PAINT WHITE (5490 210);
WIRE 16 -1 (5875 1375)(5200 1375);
FORCEPROP 0 LAST CDS_PHYS_NET_NAME SMB_SEN_3V3AUX_SCL
J 0
(5565 1423);
PAINT MONO (5565 1423);
DISPLAY INVISIBLE (5565 1423);
FORCEPROP 2 LAST SIG_NAME ADC128_A1
J 0
(5215 1385);
DISPLAY 0.510638 (5215 1385);
PAINT WHITE (5215 1385);
WIRE 16 -1 (6700 3950)(5875 3950);
FORCEPROP 0 LAST CDS_PHYS_NET_NAME P3V3_PDB_AUX_ADC_MAM
J 0
(6390 3998);
PAINT MONO (6390 3998);
DISPLAY INVISIBLE (6390 3998);
FORCEPROP 2 LAST SIG_NAME P3V3_PDB_AUX_ADC_MAM
J 0
(6140 3960);
DISPLAY 0.510638 (6140 3960);
PAINT WHITE (6140 3960);
WIRE 16 -1 (6675 3850)(5875 3850);
FORCEPROP 0 LAST CDS_PHYS_NET_NAME P3V3_AUX_ADC_MAM
J 0
(6365 3898);
PAINT MONO (6365 3898);
DISPLAY INVISIBLE (6365 3898);
FORCEPROP 2 LAST SIG_NAME P3V3_AUX_ADC_MAM
J 0
(6140 3860);
DISPLAY 0.510638 (6140 3860);
PAINT WHITE (6140 3860);
WIRE 16 2175 (5925 3050)(6500 3050);
WIRE 16 2175 (6500 3225)(6500 3050);
WIRE 16 2175 (5925 3225)(5925 3050);
WIRE 16 2175 (5925 3225)(6500 3225);
WIRE 16 -1 (4575 3150)(5425 3150);
FORCEPROP 0 LAST CDS_PHYS_NET_NAME SMB_TEMP_3V3AUX_SDA
J 0
(4615 3198);
PAINT MONO (4615 3198);
DISPLAY INVISIBLE (4615 3198);
FORCEPROP 2 LAST SIG_NAME SMB_VR_3V3AUX_SDA_R1
J 0
(4665 3160);
DISPLAY 0.510638 (4665 3160);
PAINT WHITE (4665 3160);
WIRE 16 -1 (6700 4050)(5875 4050);
FORCEPROP 0 LAST CDS_PHYS_NET_NAME P3V3_PDB_AUX_ADC_MAM
J 0
(6390 4098);
PAINT MONO (6390 4098);
DISPLAY INVISIBLE (6390 4098);
FORCEPROP 2 LAST SIG_NAME P12V_E1S_0_ISENSE_MAM
J 0
(6140 4060);
DISPLAY 0.510638 (6140 4060);
PAINT WHITE (6140 4060);
WIRE 16 2175 (6125 4125)(6700 4125);
WIRE 16 2175 (6700 4300)(6700 4125);
WIRE 16 2175 (6125 4300)(6125 4125);
WIRE 16 2175 (6125 4300)(6700 4300);
WIRE 16 -1 (6800 4150)(5875 4150);
FORCEPROP 0 LAST CDS_PHYS_NET_NAME SMB_SEN_3V3AUX_SCL
J 0
(6490 4198);
PAINT MONO (6490 4198);
DISPLAY INVISIBLE (6490 4198);
FORCEPROP 2 LAST SIG_NAME SMB_SEN_MAM_3V3AUX_SCL
J 0
(6140 4160);
DISPLAY 0.510638 (6140 4160);
PAINT WHITE (6140 4160);
WIRE 16 -1 (6525 3100)(5625 3100);
FORCEPROP 0 LAST CDS_PHYS_NET_NAME SMB_TMP75_2_3V3AUX_SCL_R
J 0
(6065 3148);
PAINT MONO (6065 3148);
DISPLAY INVISIBLE (6065 3148);
FORCEPROP 2 LAST SIG_NAME SMB_SEN_MAM_3V3AUX_SCL
J 0
(5940 3110);
DISPLAY 0.510638 (5940 3110);
PAINT WHITE (5940 3110);
WIRE 16 -1 (5875 925)(5200 925);
FORCEPROP 0 LAST CDS_PHYS_NET_NAME P3V3_AUX_ADC_TIC
J 0
(5565 973);
PAINT MONO (5565 973);
DISPLAY INVISIBLE (5565 973);
FORCEPROP 2 LAST SIG_NAME P12V_OCP_SFF_ISENSE_TIC
J 0
(5215 935);
DISPLAY 0.510638 (5215 935);
PAINT WHITE (5215 935);
WIRE 16 -1 (5875 875)(5200 875);
FORCEPROP 0 LAST CDS_PHYS_NET_NAME SMB_SEN_3V3AUX_SCL
J 0
(5565 923);
PAINT MONO (5565 923);
DISPLAY INVISIBLE (5565 923);
FORCEPROP 2 LAST SIG_NAME P12V_AUX_ADC_TIC
J 0
(5215 885);
DISPLAY 0.510638 (5215 885);
PAINT WHITE (5215 885);
WIRE 16 -1 (6675 3750)(5875 3750);
FORCEPROP 0 LAST CDS_PHYS_NET_NAME P3V3_ADC_MAM
J 0
(6365 3798);
PAINT MONO (6365 3798);
DISPLAY INVISIBLE (6365 3798);
FORCEPROP 2 LAST SIG_NAME P3V3_ADC_MAM
J 0
(6140 3760);
DISPLAY 0.510638 (6140 3760);
PAINT WHITE (6140 3760);
WIRE 16 -1 (5875 4350)(6000 4350);
WIRE 16 -1 (1375 5050)(2150 5050);
FORCEPROP 0 LAST CDS_PHYS_NET_NAME P12V_OCP_SFF_ISENSE_MPS_MAM
J 0
(2015 5098);
PAINT MONO (2015 5098);
DISPLAY INVISIBLE (2015 5098);
FORCEPROP 2 LAST SIG_NAME P12V_OCP_SFF_ISENSE_MPS_MAM
J 0
(1415 5060);
DISPLAY 0.510638 (1415 5060);
PAINT WHITE (1415 5060);
WIRE 16 -1 (4975 4725)(4525 4725);
FORCEPROP 2 LAST SIG_NAME MAX11617_VREF_R
J 0
(4815 4735);
DISPLAY 0.638298 (4815 4735);
PAINT WHITE (4815 4735);
WIRE 16 -1 (5075 4450)(4975 4450);
WIRE 16 -1 (4975 4450)(4975 4725);
WIRE 16 -1 (-475 3700)(-575 3700);
WIRE 16 -1 (-1000 3850)(-1000 3725);
WIRE 16 -1 (-1000 4000)(-1000 3850);
WIRE 16 -1 (-575 3850)(-1000 3850);
FORCEPROP 2 LAST SIG_NAME P3V3_ADC
J 0
(-910 3860);
DISPLAY 0.510638 (-910 3860);
PAINT WHITE (-910 3860);
WIRE 16 -1 (-575 3850)(-575 3700);
WIRE 16 -1 (-575 3850)(-475 3850);
FORCEPROP 0 LAST CDS_PHYS_NET_NAME P3V3_AUX_SENSE
J 0
(-460 3898);
PAINT MONO (-460 3898);
DISPLAY INVISIBLE (-460 3898);
WIRE 16 -1 (5875 975)(5200 975);
FORCEPROP 0 LAST CDS_PHYS_NET_NAME P3V3_PDB_AUX_ADC_TIC
J 0
(5565 1023);
PAINT MONO (5565 1023);
DISPLAY INVISIBLE (5565 1023);
FORCEPROP 2 LAST SIG_NAME P12V_OCP_V3_2_ISENSE_TIC
J 0
(5215 985);
DISPLAY 0.510638 (5215 985);
PAINT WHITE (5215 985);
WIRE 16 -1 (6800 4250)(5875 4250);
FORCEPROP 0 LAST CDS_PHYS_NET_NAME SMB_TMP75_2_3V3AUX_SCL_R
J 0
(6490 4298);
PAINT MONO (6490 4298);
DISPLAY INVISIBLE (6490 4298);
FORCEPROP 2 LAST SIG_NAME SMB_SEN_MAM_3V3AUX_SDA
J 0
(6140 4260);
DISPLAY 0.510638 (6140 4260);
PAINT WHITE (6140 4260);
WIRE 16 -1 (3350 175)(3350 25);
WIRE 16 -1 (3350 425)(3350 175);
WIRE 16 -1 (4425 175)(3350 175);
FORCEPROP 0 LAST CDS_PHYS_NET_NAME TCA9539_0_ADD1
J 0
(4040 217);
PAINT MONO (4040 217);
DISPLAY INVISIBLE (4040 217);
FORCEPROP 2 LAST SIG_NAME ADC128_A1
J 0
(3815 185);
DISPLAY 0.553191 (3815 185);
PAINT WHITE (3815 185);
WIRE 16 -1 (3600 275)(3600 25);
WIRE 16 -1 (3600 425)(3600 275);
WIRE 16 -1 (3600 275)(4425 275);
FORCEPROP 0 LAST CDS_PHYS_NET_NAME TCA9539_0_ADD0
J 0
(4040 317);
PAINT MONO (4040 317);
DISPLAY INVISIBLE (4040 317);
FORCEPROP 2 LAST SIG_NAME ADC128_A0
J 0
(3815 285);
DISPLAY 0.553191 (3815 285);
PAINT WHITE (3815 285);
WIRE 16 -1 (5875 4450)(6025 4450);
WIRE 16 -1 (6025 4450)(6025 4725);
WIRE 16 -1 (6025 4725)(6400 4725);
FORCEPROP 2 LAST SIG_NAME P3V3_MAX11617 _VDD
J 0
(6090 4735);
DISPLAY 0.510638 (6090 4735);
PAINT WHITE (6090 4735);
WIRE 16 -1 (6400 4625)(6400 4725);
WIRE 16 -1 (6775 4725)(6400 4725);
WIRE 16 -1 (7000 4725)(6775 4725);
WIRE 16 -1 (6775 4625)(6775 4725);
WIRE 16 -1 (4075 4650)(4075 4725);
WIRE 16 -1 (4325 4725)(4075 4725);
WIRE 16 -1 (3700 4725)(4075 4725);
FORCEPROP 2 LAST SIG_NAME MAX11617_VREF
J 0
(3740 4735);
DISPLAY 0.638298 (3740 4735);
PAINT WHITE (3740 4735);
WIRE 16 -1 (3700 4650)(3700 4725);
WIRE 16 -1 (7350 250)(6450 250);
FORCEPROP 0 LAST CDS_PHYS_NET_NAME SMB_TMP75_21_3V3AUX_SDA_R
J 0
(6890 298);
PAINT MONO (6890 298);
DISPLAY INVISIBLE (6890 298);
FORCEPROP 2 LAST SIG_NAME SMB_SEN_TIC_3V3AUX_SDA
J 0
(6765 260);
DISPLAY 0.510638 (6765 260);
PAINT WHITE (6765 260);
WIRE 16 -1 (5400 250)(6250 250);
FORCEPROP 0 LAST CDS_PHYS_NET_NAME SMB_TEMP_3V3AUX_SDA
J 0
(5440 298);
PAINT MONO (5440 298);
DISPLAY INVISIBLE (5440 298);
FORCEPROP 2 LAST SIG_NAME SMB_VR_3V3AUX_SDA_R1
J 0
(5490 260);
DISPLAY 0.510638 (5490 260);
PAINT WHITE (5490 260);
WIRE 16 -1 (5875 1625)(5200 1625);
FORCEPROP 0 LAST CDS_PHYS_NET_NAME SMB_TMP75_2_3V3AUX_SCL_R
J 0
(5565 1673);
PAINT MONO (5565 1673);
DISPLAY INVISIBLE (5565 1673);
FORCEPROP 2 LAST SIG_NAME SMB_SEN_TIC_3V3AUX_SCL
J 0
(5215 1635);
DISPLAY 0.510638 (5215 1635);
PAINT WHITE (5215 1635);
WIRE 16 -1 (1375 5200)(2150 5200);
FORCEPROP 0 LAST CDS_PHYS_NET_NAME P12V_OCP_SFF_ISENSE_MAM_MAM
J 0
(2015 5248);
PAINT MONO (2015 5248);
DISPLAY INVISIBLE (2015 5248);
FORCEPROP 2 LAST SIG_NAME P12V_OCP_SFF_ISENSE_MAM_MAM
J 0
(1415 5210);
DISPLAY 0.510638 (1415 5210);
PAINT WHITE (1415 5210);
WIRE 16 -1 (5875 1125)(5200 1125);
FORCEPROP 0 LAST CDS_PHYS_NET_NAME P3V3_AUX_ADC_TIC
J 0
(5565 1173);
PAINT MONO (5565 1173);
DISPLAY INVISIBLE (5565 1173);
FORCEPROP 2 LAST SIG_NAME P3V3_AUX_ADC_TIC
J 0
(5215 1135);
DISPLAY 0.510638 (5215 1135);
PAINT WHITE (5215 1135);
WIRE 16 -1 (7350 1725)(6675 1725);
FORCEPROP 0 LAST CDS_PHYS_NET_NAME SMB_SEN_3V3AUX_SCL
J 0
(7040 1773);
PAINT MONO (7040 1773);
DISPLAY INVISIBLE (7040 1773);
FORCEPROP 2 LAST SIG_NAME TP_ADC128_INT
J 0
(6740 1735);
DISPLAY 0.510638 (6740 1735);
PAINT WHITE (6740 1735);
WIRE 16 -1 (7350 200)(6450 200);
FORCEPROP 0 LAST CDS_PHYS_NET_NAME SMB_TMP75_2_3V3AUX_SCL_R
J 0
(6890 248);
PAINT MONO (6890 248);
DISPLAY INVISIBLE (6890 248);
FORCEPROP 2 LAST SIG_NAME SMB_SEN_TIC_3V3AUX_SCL
J 0
(6765 210);
DISPLAY 0.510638 (6765 210);
PAINT WHITE (6765 210);
DOT 1 (2925 3225);
DOT 1 (2675 3225);
DOT 1 (3350 800);
DOT 1 (2900 2725);
DOT 1 (2700 3725);
DOT 1 (-475 325);
DOT 1 (-1025 1400);
DOT 1 (2700 4225);
DOT 1 (325 2700);
DOT 1 (-1000 2700);
DOT 1 (-600 2700);
DOT 1 (-25 2550);
DOT 1 (-1000 3850);
DOT 1 (-575 3850);
DOT 1 (0 3700);
DOT 1 (-1000 5175);
DOT 1 (-525 5175);
DOT 1 (350 1250);
DOT 1 (700 1400);
DOT 1 (1025 350);
DOT 1 (1375 500);
DOT 1 (350 3850);
DOT 1 (3350 175);
DOT 1 (3600 275);
DOT 1 (3725 1900);
DOT 1 (4050 1900);
DOT 1 (2675 2725);
DOT 1 (2925 3725);
DOT 1 (425 5175);
DOT 1 (1450 5600);
DOT 1 (1900 5600);
DOT 1 (1900 5475);
DOT 1 (1900 5725);
DOT 1 (2950 4225);
DOT 1 (2725 4700);
DOT 1 (2950 4700);
DOT 1 (2325 5600);
DOT 1 (2325 5475);
DOT 1 (2325 5725);
DOT 1 (2725 5200);
DOT 1 (2750 5600);
DOT 1 (2750 5475);
DOT 1 (2975 5200);
DOT 1 (2750 5725);
DOT 1 (4075 4725);
DOT 1 (3125 5475);
DOT 1 (3125 5600);
DOT 1 (3575 5600);
DOT 1 (3125 5725);
DOT 1 (4425 1900);
DOT 1 (4975 4150);
DOT 1 (4975 4250);
DOT 1 (6400 4725);
DOT 1 (6775 4725);
DOT 1 (250 500);
DOT 1 (4425 1475);
DOT 1 (75 5025);
DOT 1 (-600 1400);
FORCENOTE
ADDR: 0X3A
(5900 625) 0;
DISPLAY LEFT (5900 625);
DISPLAY 1.595745 (5900 625);
PAINT WHITE (5900 625);
FORCENOTE
ADDR: 0X6A
(5125 3325) 0;
DISPLAY LEFT (5125 3325);
DISPLAY 1.595745 (5125 3325);
PAINT WHITE (5125 3325);
FORCENOTE
V SOURCE P3V3_AUX   P3V3     P5V   P12V_AUX
(1500 5625) 0;
DISPLAY LEFT (1500 5625);
DISPLAY 1.021277 (1500 5625);
PAINT WHITE (1500 5625);
FORCENOTE
 VIN     1.599V   1.599V  1.677V   1.581V
(1550 5500) 0;
DISPLAY LEFT (1550 5500);
DISPLAY 1.021277 (1550 5500);
PAINT WHITE (1550 5500);
FORCENOTE
VI=1.581V
(-1125 300) 0;
DISPLAY LEFT (-1125 300);
DISPLAY 1.021277 (-1125 300);
PAINT WHITE (-1125 300);
FORCENOTE
20220105 ADD R4567,R4568
(-1150 -225) 0;
DISPLAY LEFT (-1150 -225);
DISPLAY 1.276596 (-1150 -225);
PAINT PINK (-1150 -225);
FORCENOTE
20210615 MODIFY FOR GT
(5100 5650) 0;
DISPLAY LEFT (5100 5650);
DISPLAY 2.510638 (5100 5650);
PAINT PINK (5100 5650);
FORCENOTE
IF USE AD128,POP R3668,R3670
(3925 25) 0;
DISPLAY LEFT (3925 25);
DISPLAY 0.808511 (3925 25);
PAINT WHITE (3925 25);
FORCENOTE
20220801 CHANGE NET NAME
(5925 3250) 0;
DISPLAY LEFT (5925 3250);
DISPLAY 1.063830 (5925 3250);
PAINT WHITE (5925 3250);
FORCENOTE
NOTE:R4567 NEED CHANGE TO 5.11K OHM ON EVT STATES AND POP R4568
(-1150 -300) 0;
DISPLAY LEFT (-1150 -300);
DISPLAY 1.021277 (-1150 -300);
PAINT WHITE (-1150 -300);
QUIT
